FILE_TYPE = MACRO_DRAWING;
SET COLOR_WIRE YELLOW;
SET COLOR_PROP ORANGE;
SET COLOR_DOT WHITE;
SET COLOR_ARC YELLOW;
SET COLOR_BODY GREEN;
SET COLOR_NOTE PURPLE;
SET PROP_DISPLAY VALUE;
SET PAGE_NUMBER P313;
FORCEADD LCMXO3LF9400C5BG484C..7
(575 500);
FORCEPROP 1 LAST PART_NUMBER AJ094000T08
J 0
(97 1920);
DISPLAY 0.723404 (97 1920);
PAINT GREEN (97 1920);
DISPLAY INVISIBLE (97 1920);
FORCEPROP 2 LAST PART_TYPE SMLF
J 0
(100 2175);
DISPLAY 1.021277 (100 2175);
FORCEPROP 2 LAST VALUE LCMXO3LF-9400C-5BG484C
J 0
(100 2125);
DISPLAY 1.021277 (100 2125);
FORCEPROP 1 LAST MATERIAL IC
J 0
(97 1793);
DISPLAY 0.723404 (97 1793);
PAINT GREEN (97 1793);
FORCEPROP 1 LAST $LOCATION U249
J 0
(97 2067);
DISPLAY 0.723404 (97 2067);
PAINT GREEN (97 2067);
FORCEPROP 0 LASTPIN (-50 1675) $PN C21
J 2
(-60 1685);
DISPLAY 0.680851 (-60 1685);
PAINT MONO (-60 1685);
FORCEPROP 0 LASTPIN (-50 1625) $PN C22
J 2
(-60 1635);
DISPLAY 0.680851 (-60 1635);
PAINT MONO (-60 1635);
FORCEPROP 0 LASTPIN (-50 1575) $PN F17
J 2
(-60 1585);
DISPLAY 0.680851 (-60 1585);
PAINT MONO (-60 1585);
FORCEPROP 0 LASTPIN (-50 1525) $PN G16
J 2
(-60 1535);
DISPLAY 0.680851 (-60 1535);
PAINT MONO (-60 1535);
FORCEPROP 0 LASTPIN (-50 1475) $PN D22
J 2
(-60 1485);
DISPLAY 0.680851 (-60 1485);
PAINT MONO (-60 1485);
FORCEPROP 0 LASTPIN (-50 1425) $PN D21
J 2
(-60 1435);
DISPLAY 0.680851 (-60 1435);
PAINT MONO (-60 1435);
FORCEPROP 0 LASTPIN (-50 1375) $PN D19
J 2
(-60 1385);
DISPLAY 0.680851 (-60 1385);
PAINT MONO (-60 1385);
FORCEPROP 0 LASTPIN (-50 1325) $PN D20
J 2
(-60 1335);
DISPLAY 0.680851 (-60 1335);
PAINT MONO (-60 1335);
FORCEPROP 0 LASTPIN (-50 1275) $PN E22
J 2
(-60 1285);
DISPLAY 0.680851 (-60 1285);
PAINT MONO (-60 1285);
FORCEPROP 0 LASTPIN (-50 1225) $PN E21
J 2
(-60 1235);
DISPLAY 0.680851 (-60 1235);
PAINT MONO (-60 1235);
FORCEPROP 0 LASTPIN (-50 1175) $PN E19
J 2
(-60 1185);
DISPLAY 0.680851 (-60 1185);
PAINT MONO (-60 1185);
FORCEPROP 0 LASTPIN (-50 1125) $PN E20
J 2
(-60 1135);
DISPLAY 0.680851 (-60 1135);
PAINT MONO (-60 1135);
FORCEPROP 0 LASTPIN (-50 1075) $PN F22
J 2
(-60 1085);
DISPLAY 0.680851 (-60 1085);
PAINT MONO (-60 1085);
FORCEPROP 0 LASTPIN (-50 1025) $PN G22
J 2
(-60 1035);
DISPLAY 0.680851 (-60 1035);
PAINT MONO (-60 1035);
FORCEPROP 0 LASTPIN (-50 975) $PN F18
J 2
(-60 985);
DISPLAY 0.680851 (-60 985);
PAINT MONO (-60 985);
FORCEPROP 0 LASTPIN (-50 925) $PN F19
J 2
(-60 935);
DISPLAY 0.680851 (-60 935);
PAINT MONO (-60 935);
FORCEPROP 0 LASTPIN (-50 875) $PN G21
J 2
(-60 885);
DISPLAY 0.680851 (-60 885);
PAINT MONO (-60 885);
FORCEPROP 0 LASTPIN (-50 825) $PN G20
J 2
(-60 835);
DISPLAY 0.680851 (-60 835);
PAINT MONO (-60 835);
FORCEPROP 0 LASTPIN (-50 775) $PN G19
J 2
(-60 785);
DISPLAY 0.680851 (-60 785);
PAINT MONO (-60 785);
FORCEPROP 0 LASTPIN (-50 725) $PN G18
J 2
(-60 735);
DISPLAY 0.680851 (-60 735);
PAINT MONO (-60 735);
FORCEPROP 0 LASTPIN (-50 675) $PN H22
J 2
(-60 685);
DISPLAY 0.680851 (-60 685);
PAINT MONO (-60 685);
FORCEPROP 0 LASTPIN (-50 625) $PN H21
J 2
(-60 635);
DISPLAY 0.680851 (-60 635);
PAINT MONO (-60 635);
FORCEPROP 0 LASTPIN (-50 575) $PN G17
J 2
(-60 585);
DISPLAY 0.680851 (-60 585);
PAINT MONO (-60 585);
FORCEPROP 0 LASTPIN (-50 525) $PN H20
J 2
(-60 535);
DISPLAY 0.680851 (-60 535);
PAINT MONO (-60 535);
FORCEPROP 0 LASTPIN (-50 475) $PN H19
J 2
(-60 485);
DISPLAY 0.680851 (-60 485);
PAINT MONO (-60 485);
FORCEPROP 0 LASTPIN (-50 425) $PN H18
J 2
(-60 435);
DISPLAY 0.680851 (-60 435);
PAINT MONO (-60 435);
FORCEPROP 0 LASTPIN (-50 375) $PN H17
J 2
(-60 385);
DISPLAY 0.680851 (-60 385);
PAINT MONO (-60 385);
FORCEPROP 0 LASTPIN (-50 325) $PN H16
J 2
(-60 335);
DISPLAY 0.680851 (-60 335);
PAINT MONO (-60 335);
FORCEPROP 0 LASTPIN (-50 275) $PN J16
J 2
(-60 285);
DISPLAY 0.680851 (-60 285);
PAINT MONO (-60 285);
FORCEPROP 0 LASTPIN (-50 225) $PN J17
J 2
(-60 235);
DISPLAY 0.680851 (-60 235);
PAINT MONO (-60 235);
FORCEPROP 0 LASTPIN (-50 175) $PN J18
J 2
(-60 185);
DISPLAY 0.680851 (-60 185);
PAINT MONO (-60 185);
FORCEPROP 0 LASTPIN (-50 125) $PN J19
J 2
(-60 135);
DISPLAY 0.680851 (-60 135);
PAINT MONO (-60 135);
FORCEPROP 0 LASTPIN (-50 75) $PN J21
J 2
(-60 85);
DISPLAY 0.680851 (-60 85);
PAINT MONO (-60 85);
FORCEPROP 0 LASTPIN (-50 25) $PN J22
J 2
(-60 35);
DISPLAY 0.680851 (-60 35);
PAINT MONO (-60 35);
FORCEPROP 0 LASTPIN (-50 -25) $PN J20
J 2
(-60 -15);
DISPLAY 0.680851 (-60 -15);
PAINT MONO (-60 -15);
FORCEPROP 0 LASTPIN (-50 -75) $PN K20
J 2
(-60 -65);
DISPLAY 0.680851 (-60 -65);
PAINT MONO (-60 -65);
FORCEPROP 0 LASTPIN (-50 -125) $PN K19
J 2
(-60 -115);
DISPLAY 0.680851 (-60 -115);
PAINT MONO (-60 -115);
FORCEPROP 0 LASTPIN (-50 -175) $PN K18
J 2
(-60 -165);
DISPLAY 0.680851 (-60 -165);
PAINT MONO (-60 -165);
FORCEPROP 0 LASTPIN (-50 -225) $PN K17
J 2
(-60 -215);
DISPLAY 0.680851 (-60 -215);
PAINT MONO (-60 -215);
FORCEPROP 0 LASTPIN (-50 -275) $PN K16
J 2
(-60 -265);
DISPLAY 0.680851 (-60 -265);
PAINT MONO (-60 -265);
FORCEPROP 0 LASTPIN (-50 -325) $PN L17
J 2
(-60 -315);
DISPLAY 0.680851 (-60 -315);
PAINT MONO (-60 -315);
FORCEPROP 0 LASTPIN (-50 -375) $PN L16
J 2
(-60 -365);
DISPLAY 0.680851 (-60 -365);
PAINT MONO (-60 -365);
FORCEPROP 0 LASTPIN (-50 -425) $PN L19
J 2
(-60 -415);
DISPLAY 0.680851 (-60 -415);
PAINT MONO (-60 -415);
FORCEPROP 0 LASTPIN (-50 -475) $PN L20
J 2
(-60 -465);
DISPLAY 0.680851 (-60 -465);
PAINT MONO (-60 -465);
FORCEPROP 0 LASTPIN (-50 -525) $PN K22
J 2
(-60 -515);
DISPLAY 0.680851 (-60 -515);
PAINT MONO (-60 -515);
FORCEPROP 0 LASTPIN (-50 -575) $PN L21
J 2
(-60 -565);
DISPLAY 0.680851 (-60 -565);
PAINT MONO (-60 -565);
FORCEPROP 0 LASTPIN (-50 -625) $PN L22
J 2
(-60 -615);
DISPLAY 0.680851 (-60 -615);
PAINT MONO (-60 -615);
FORCEPROP 0 LASTPIN (-50 -675) $PN M17
J 2
(-60 -665);
DISPLAY 0.680851 (-60 -665);
PAINT MONO (-60 -665);
FORCEPROP 0 LASTPIN (1200 1675) $PN M22
J 0
(1210 1685);
DISPLAY 0.680851 (1210 1685);
PAINT MONO (1210 1685);
FORCEPROP 0 LASTPIN (1200 1625) $PN M21
J 0
(1210 1635);
DISPLAY 0.680851 (1210 1635);
PAINT MONO (1210 1635);
FORCEPROP 0 LASTPIN (1200 1575) $PN M20
J 0
(1210 1585);
DISPLAY 0.680851 (1210 1585);
PAINT MONO (1210 1585);
FORCEPROP 0 LASTPIN (1200 1525) $PN M19
J 0
(1210 1535);
DISPLAY 0.680851 (1210 1535);
PAINT MONO (1210 1535);
FORCEPROP 0 LASTPIN (1200 1475) $PN M16
J 0
(1210 1485);
DISPLAY 0.680851 (1210 1485);
PAINT MONO (1210 1485);
FORCEPROP 0 LASTPIN (1200 1425) $PN N16
J 0
(1210 1435);
DISPLAY 0.680851 (1210 1435);
PAINT MONO (1210 1435);
FORCEPROP 0 LASTPIN (1200 1375) $PN N17
J 0
(1210 1385);
DISPLAY 0.680851 (1210 1385);
PAINT MONO (1210 1385);
FORCEPROP 0 LASTPIN (1200 1325) $PN N18
J 0
(1210 1335);
DISPLAY 0.680851 (1210 1335);
PAINT MONO (1210 1335);
FORCEPROP 0 LASTPIN (1200 1275) $PN N22
J 0
(1210 1285);
DISPLAY 0.680851 (1210 1285);
PAINT MONO (1210 1285);
FORCEPROP 0 LASTPIN (1200 1225) $PN P21
J 0
(1210 1235);
DISPLAY 0.680851 (1210 1235);
PAINT MONO (1210 1235);
FORCEPROP 0 LASTPIN (1200 1175) $PN N20
J 0
(1210 1185);
DISPLAY 0.680851 (1210 1185);
PAINT MONO (1210 1185);
FORCEPROP 0 LASTPIN (1200 1125) $PN N19
J 0
(1210 1135);
DISPLAY 0.680851 (1210 1135);
PAINT MONO (1210 1135);
FORCEPROP 0 LASTPIN (1200 1075) $PN R22
J 0
(1210 1085);
DISPLAY 0.680851 (1210 1085);
PAINT MONO (1210 1085);
FORCEPROP 0 LASTPIN (1200 1025) $PN R21
J 0
(1210 1035);
DISPLAY 0.680851 (1210 1035);
PAINT MONO (1210 1035);
FORCEPROP 0 LASTPIN (1200 975) $PN P22
J 0
(1210 985);
DISPLAY 0.680851 (1210 985);
PAINT MONO (1210 985);
FORCEPROP 0 LASTPIN (1200 925) $PN P20
J 0
(1210 935);
DISPLAY 0.680851 (1210 935);
PAINT MONO (1210 935);
FORCEPROP 0 LASTPIN (1200 875) $PN T22
J 0
(1210 885);
DISPLAY 0.680851 (1210 885);
PAINT MONO (1210 885);
FORCEPROP 0 LASTPIN (1200 825) $PN T21
J 0
(1210 835);
DISPLAY 0.680851 (1210 835);
PAINT MONO (1210 835);
FORCEPROP 0 LASTPIN (1200 775) $PN P19
J 0
(1210 785);
DISPLAY 0.680851 (1210 785);
PAINT MONO (1210 785);
FORCEPROP 0 LASTPIN (1200 725) $PN P18
J 0
(1210 735);
DISPLAY 0.680851 (1210 735);
PAINT MONO (1210 735);
FORCEPROP 0 LASTPIN (1200 675) $PN P17
J 0
(1210 685);
DISPLAY 0.680851 (1210 685);
PAINT MONO (1210 685);
FORCEPROP 0 LASTPIN (1200 625) $PN P16
J 0
(1210 635);
DISPLAY 0.680851 (1210 635);
PAINT MONO (1210 635);
FORCEPROP 0 LASTPIN (1200 575) $PN U22
J 0
(1210 585);
DISPLAY 0.680851 (1210 585);
PAINT MONO (1210 585);
FORCEPROP 0 LASTPIN (1200 525) $PN U21
J 0
(1210 535);
DISPLAY 0.680851 (1210 535);
PAINT MONO (1210 535);
FORCEPROP 0 LASTPIN (1200 475) $PN V22
J 0
(1210 485);
DISPLAY 0.680851 (1210 485);
PAINT MONO (1210 485);
FORCEPROP 0 LASTPIN (1200 425) $PN W22
J 0
(1210 435);
DISPLAY 0.680851 (1210 435);
PAINT MONO (1210 435);
FORCEPROP 0 LASTPIN (1200 375) $PN R20
J 0
(1210 385);
DISPLAY 0.680851 (1210 385);
PAINT MONO (1210 385);
FORCEPROP 0 LASTPIN (1200 325) $PN R19
J 0
(1210 335);
DISPLAY 0.680851 (1210 335);
PAINT MONO (1210 335);
FORCEPROP 0 LASTPIN (1200 225) $PN R18
J 0
(1210 235);
DISPLAY 0.680851 (1210 235);
PAINT MONO (1210 235);
FORCEPROP 0 LASTPIN (1200 175) $PN R17
J 0
(1210 185);
DISPLAY 0.680851 (1210 185);
PAINT MONO (1210 185);
FORCEPROP 0 LASTPIN (1200 125) $PN R16
J 0
(1210 135);
DISPLAY 0.680851 (1210 135);
PAINT MONO (1210 135);
FORCEPROP 0 LASTPIN (1200 75) $PN T20
J 0
(1210 85);
DISPLAY 0.680851 (1210 85);
PAINT MONO (1210 85);
FORCEPROP 0 LASTPIN (1200 25) $PN T19
J 0
(1210 35);
DISPLAY 0.680851 (1210 35);
PAINT MONO (1210 35);
FORCEPROP 0 LASTPIN (1200 -25) $PN T18
J 0
(1210 -15);
DISPLAY 0.680851 (1210 -15);
PAINT MONO (1210 -15);
FORCEPROP 0 LASTPIN (1200 -75) $PN T17
J 0
(1210 -65);
DISPLAY 0.680851 (1210 -65);
PAINT MONO (1210 -65);
FORCEPROP 0 LASTPIN (1200 -125) $PN U20
J 0
(1210 -115);
DISPLAY 0.680851 (1210 -115);
PAINT MONO (1210 -115);
FORCEPROP 0 LASTPIN (1200 -175) $PN Y22
J 0
(1210 -165);
DISPLAY 0.680851 (1210 -165);
PAINT MONO (1210 -165);
FORCEPROP 0 LASTPIN (1200 -225) $PN W21
J 0
(1210 -215);
DISPLAY 0.680851 (1210 -215);
PAINT MONO (1210 -215);
FORCEPROP 0 LASTPIN (1200 -275) $PN U19
J 0
(1210 -265);
DISPLAY 0.680851 (1210 -265);
PAINT MONO (1210 -265);
FORCEPROP 0 LASTPIN (1200 -325) $PN U18
J 0
(1210 -315);
DISPLAY 0.680851 (1210 -315);
PAINT MONO (1210 -315);
FORCEPROP 0 LASTPIN (1200 -375) $PN AA22
J 0
(1210 -365);
DISPLAY 0.680851 (1210 -365);
PAINT MONO (1210 -365);
FORCEPROP 0 LASTPIN (1200 -425) $PN Y21
J 0
(1210 -415);
DISPLAY 0.680851 (1210 -415);
PAINT MONO (1210 -415);
FORCEPROP 0 LASTPIN (1200 -475) $PN U17
J 0
(1210 -465);
DISPLAY 0.680851 (1210 -465);
PAINT MONO (1210 -465);
FORCEPROP 0 LASTPIN (1200 -525) $PN V19
J 0
(1210 -515);
DISPLAY 0.680851 (1210 -515);
PAINT MONO (1210 -515);
FORCEPROP 0 LASTPIN (1200 -575) $PN V18
J 0
(1210 -565);
DISPLAY 0.680851 (1210 -565);
PAINT MONO (1210 -565);
FORCEPROP 0 LASTPIN (1200 -625) $PN W20
J 0
(1210 -615);
DISPLAY 0.680851 (1210 -615);
PAINT MONO (1210 -615);
FORCEPROP 0 LASTPIN (1200 -675) $PN W19
J 0
(1210 -665);
DISPLAY 0.680851 (1210 -665);
PAINT MONO (1210 -665);
FORCEPROP 0 LASTPIN (1200 -725) $PN Y20
J 0
(1210 -715);
DISPLAY 0.680851 (1210 -715);
PAINT MONO (1210 -715);
FORCEPROP 1 LAST PATH I1
J 0
(575 500);
DISPLAY 0.723404 (575 500);
PAINT GREEN (575 500);
DISPLAY INVISIBLE (575 500);
FORCEPROP 2 LAST CDS_LIB pure_quanta
J 0
(575 500);
DISPLAY INVISIBLE (575 500);
FORCEPROP 1 LAST NEEDS_NO_SIZE TRUE
J 0
(575 500);
DISPLAY 0.723404 (575 500);
PAINT GREEN (575 500);
DISPLAY INVISIBLE (575 500);
FORCEPROP 1 LAST CDS_LMAN_SYM_OUTLINE -475,1275,475,-1275
J 0
(575 500);
DISPLAY 0.468085 (575 500);
PAINT GREEN (575 500);
DISPLAY INVISIBLE (575 500);
FORCEPROP 0 LAST CDS_LOCATION U249
J 0
(100 2225);
DISPLAY 1.021277 (100 2225);
DISPLAY INVISIBLE (100 2225);
FORCEPROP 0 LAST $SEC 7
J 0
(100 2225);
DISPLAY 0.680851 (100 2225);
PAINT MONO (100 2225);
DISPLAY INVISIBLE (100 2225);
FORCEPROP 0 LAST CDS_SEC 7
J 0
(100 2225);
DISPLAY 1.021277 (100 2225);
DISPLAY INVISIBLE (100 2225);
FORCEADD OFFPAGE..1
R 2
(2400 1275);
FORCEPROP 2 LAST $XR1 119 
J 0
(2676 1275);
DISPLAY 0.638298 (2676 1275);
PAINT MONO (2676 1275);
FORCEPROP 2 LAST $XR0 44 
J 0
(2586 1275);
DISPLAY 0.638298 (2586 1275);
PAINT MONO (2586 1275);
FORCEPROP 2 LAST PATH I10
J 0
(2700 1325);
DISPLAY 1.021277 (2700 1325);
DISPLAY INVISIBLE (2700 1325);
FORCEPROP 2 LAST CDS_LIB standard
J 2
(2400 1275);
DISPLAY INVISIBLE (2400 1275);
FORCEPROP 1 LAST OFFPAGE TRUE
J 2
(2075 1150);
DISPLAY 0.872340 (2075 1150);
DISPLAY INVISIBLE (2075 1150);
FORCEPROP 1 LAST COMMENT_BODY TRUE
J 2
(2275 1175);
DISPLAY 1.170213 (2275 1175);
PAINT GREEN (2275 1175);
DISPLAY INVISIBLE (2275 1175);
FORCEADD OFFPAGE..1
(1400 -1600);
FORCEPROP 2 LAST $XR0 214 
J 0
(1118 -1600);
DISPLAY 0.638298 (1118 -1600);
PAINT MONO (1118 -1600);
FORCEPROP 2 LAST CDS_LIB standard
J 0
(1400 -1600);
DISPLAY INVISIBLE (1400 -1600);
FORCEPROP 1 LAST COMMENT_BODY TRUE
J 0
(1525 -1700);
DISPLAY 1.170213 (1525 -1700);
PAINT GREEN (1525 -1700);
DISPLAY INVISIBLE (1525 -1700);
FORCEPROP 1 LAST OFFPAGE TRUE
J 0
(1725 -1725);
DISPLAY 0.872340 (1725 -1725);
DISPLAY INVISIBLE (1725 -1725);
FORCEPROP 2 LAST PATH I100
J 0
(1125 -1550);
DISPLAY 1.021277 (1125 -1550);
DISPLAY INVISIBLE (1125 -1550);
FORCEADD OFFPAGE..1
(1375 -1800);
FORCEPROP 2 LAST $XR3 259 
J 0
(733 -1800);
DISPLAY 0.638298 (733 -1800);
PAINT MONO (733 -1800);
FORCEPROP 2 LAST $XR2 247 
J 0
(853 -1800);
DISPLAY 0.638298 (853 -1800);
PAINT MONO (853 -1800);
FORCEPROP 2 LAST $XR1 305 
J 0
(973 -1800);
DISPLAY 0.638298 (973 -1800);
PAINT MONO (973 -1800);
FORCEPROP 2 LAST $XR0 301 
J 0
(1093 -1800);
DISPLAY 0.638298 (1093 -1800);
PAINT MONO (1093 -1800);
FORCEPROP 2 LAST CDS_LIB standard
J 0
(1375 -1800);
DISPLAY INVISIBLE (1375 -1800);
FORCEPROP 1 LAST COMMENT_BODY TRUE
J 0
(1500 -1900);
DISPLAY 1.170213 (1500 -1900);
PAINT GREEN (1500 -1900);
DISPLAY INVISIBLE (1500 -1900);
FORCEPROP 1 LAST OFFPAGE TRUE
J 0
(1700 -1925);
DISPLAY 0.872340 (1700 -1925);
DISPLAY INVISIBLE (1700 -1925);
FORCEPROP 2 LAST PATH I104
J 0
(1100 -1750);
DISPLAY 1.021277 (1100 -1750);
DISPLAY INVISIBLE (1100 -1750);
FORCEADD OFFPAGE..2
(625 -3025);
FORCEPROP 2 LAST $XR0 215 
J 0
(814 -3025);
DISPLAY 0.638298 (814 -3025);
PAINT MONO (814 -3025);
FORCEPROP 1 LAST COMMENT_BODY TRUE
J 0
(580 -3120);
DISPLAY 1.170213 (580 -3120);
PAINT GREEN (580 -3120);
DISPLAY INVISIBLE (580 -3120);
FORCEPROP 1 LAST OFFPAGE TRUE
J 0
(950 -3150);
DISPLAY 1.170213 (950 -3150);
PAINT GREEN (950 -3150);
DISPLAY INVISIBLE (950 -3150);
FORCEPROP 2 LAST CDS_LIB standard
J 0
(625 -3025);
PAINT MONO (625 -3025);
DISPLAY INVISIBLE (625 -3025);
FORCEPROP 2 LAST PATH I105
J 0
(825 -2975);
DISPLAY 1.021277 (825 -2975);
DISPLAY INVISIBLE (825 -2975);
FORCEADD OFFPAGE..1
R 2
(2400 1325);
FORCEPROP 2 LAST $XR1 119 
J 0
(2676 1325);
DISPLAY 0.638298 (2676 1325);
PAINT MONO (2676 1325);
FORCEPROP 2 LAST $XR0 13 
J 0
(2586 1325);
DISPLAY 0.638298 (2586 1325);
PAINT MONO (2586 1325);
FORCEPROP 2 LAST PATH I11
J 0
(2700 1375);
DISPLAY 1.021277 (2700 1375);
DISPLAY INVISIBLE (2700 1375);
FORCEPROP 2 LAST CDS_LIB standard
J 0
(2400 1325);
DISPLAY INVISIBLE (2400 1325);
FORCEPROP 1 LAST COMMENT_BODY TRUE
J 2
(2275 1225);
DISPLAY 1.170213 (2275 1225);
PAINT GREEN (2275 1225);
DISPLAY INVISIBLE (2275 1225);
FORCEPROP 1 LAST OFFPAGE TRUE
J 2
(2075 1200);
DISPLAY 1.170213 (2075 1200);
PAINT GREEN (2075 1200);
DISPLAY INVISIBLE (2075 1200);
FORCEADD Q_RES..1
(-950 -3025);
FORCEPROP 1 LAST PART_NUMBER CS03322FB03
J 0
(-1100 -2950);
DISPLAY 0.638298 (-1100 -2950);
DISPLAY INVISIBLE (-1100 -2950);
FORCEPROP 1 LAST WATTAGE 1/16W
J 2
(-750 -2900);
DISPLAY 0.638298 (-750 -2900);
FORCEPROP 1 LAST PACK_TYPE 0402LF
J 0
(-1100 -2900);
DISPLAY 0.638298 (-1100 -2900);
FORCEPROP 1 LAST VALUE 33.2
J 2
(-700 -3025);
DISPLAY 0.638298 (-700 -3025);
FORCEPROP 1 LAST TOLERANCE 1%
J 0
(-675 -3025);
DISPLAY 0.638298 (-675 -3025);
FORCEPROP 1 LAST MATERIAL CHIP
J 0
(-600 -3025);
DISPLAY 0.638298 (-600 -3025);
FORCEPROP 1 LAST $LOCATION R1100
J 0
(-1225 -3025);
DISPLAY 0.787234 (-1225 -3025);
FORCEPROP 1 LASTPIN (-1050 -3025) $PN 1
J 0
(-1038 -3013);
DISPLAY 0.787234 (-1038 -3013);
FORCEPROP 1 LASTPIN (-850 -3025) $PN 2
J 0
(-888 -3013);
DISPLAY 0.787234 (-888 -3013);
FORCEPROP 2 LAST CDS_LIB pure_quanta
J 0
(-950 -3025);
PAINT MONO (-950 -3025);
DISPLAY INVISIBLE (-950 -3025);
FORCEPROP 1 LAST PATH I115
J 0
(-1000 -2875);
DISPLAY 0.978723 (-1000 -2875);
PAINT WHITE (-1000 -2875);
DISPLAY INVISIBLE (-1000 -2875);
FORCEPROP 2 LAST CDS_LOCATION R1100
J 0
(-1000 -2825);
DISPLAY 1.021277 (-1000 -2825);
DISPLAY INVISIBLE (-1000 -2825);
FORCEPROP 2 LAST $SEC 1
J 0
(-1000 -2825);
DISPLAY 0.680851 (-1000 -2825);
PAINT MONO (-1000 -2825);
DISPLAY INVISIBLE (-1000 -2825);
FORCEPROP 2 LAST CDS_SEC 1
J 0
(-1000 -2825);
DISPLAY 1.021277 (-1000 -2825);
DISPLAY INVISIBLE (-1000 -2825);
FORCEADD OFFPAGE..1
R 2
(2400 1225);
FORCEPROP 2 LAST $XR1 119 
J 0
(2676 1225);
DISPLAY 0.638298 (2676 1225);
PAINT MONO (2676 1225);
FORCEPROP 2 LAST $XR0 44 
J 0
(2586 1225);
DISPLAY 0.638298 (2586 1225);
PAINT MONO (2586 1225);
FORCEPROP 2 LAST PATH I12
J 0
(2700 1275);
DISPLAY 1.021277 (2700 1275);
DISPLAY INVISIBLE (2700 1275);
FORCEPROP 1 LAST OFFPAGE TRUE
J 2
(2075 1100);
DISPLAY 1.170213 (2075 1100);
PAINT GREEN (2075 1100);
DISPLAY INVISIBLE (2075 1100);
FORCEPROP 1 LAST COMMENT_BODY TRUE
J 2
(2275 1125);
DISPLAY 1.170213 (2275 1125);
PAINT GREEN (2275 1125);
DISPLAY INVISIBLE (2275 1125);
FORCEPROP 2 LAST CDS_LIB standard
J 0
(2400 1225);
DISPLAY INVISIBLE (2400 1225);
FORCEADD UNIVERSAL_GND..1
(-2000 -3275);
FORCEPROP 3 LASTPIN (-2000 -3225) SIG_NAME GND\g
J 0
(-1990 -3215);
DISPLAY 0.659574 (-1990 -3215);
PAINT MONO (-1990 -3215);
DISPLAY INVISIBLE (-1990 -3215);
FORCEPROP 1 LAST PATH I123
J 0
(-1925 -3275);
DISPLAY 0.872340 (-1925 -3275);
PAINT AQUA (-1925 -3275);
DISPLAY INVISIBLE (-1925 -3275);
FORCEPROP 2 LAST CDS_LIB logical_power
J 0
(-2000 -3275);
PAINT MONO (-2000 -3275);
DISPLAY INVISIBLE (-2000 -3275);
FORCEPROP 1 LAST HDL_POWER GND
J 1
(-1975 -3350);
DISPLAY 0.872340 (-1975 -3350);
PAINT GREEN (-1975 -3350);
DISPLAY INVISIBLE (-1975 -3350);
FORCEADD UNIVERSAL_POWER..1
(-3000 -2450);
FORCEPROP 3 LASTPIN (-3000 -2500) SIG_NAME P3V3_AUX\g
J 0
(-2990 -2490);
DISPLAY 0.659574 (-2990 -2490);
PAINT MONO (-2990 -2490);
DISPLAY INVISIBLE (-2990 -2490);
FORCEPROP 1 LAST HDL_POWER P3V3_AUX
J 1
(-3000 -2400);
DISPLAY 0.872340 (-3000 -2400);
PAINT GREEN (-3000 -2400);
FORCEPROP 2 LAST CDS_LIB logical_power
J 0
(-3000 -2450);
PAINT MONO (-3000 -2450);
DISPLAY INVISIBLE (-3000 -2450);
FORCEPROP 1 LAST PATH I124
J 0
(-2950 -2425);
DISPLAY 0.872340 (-2950 -2425);
PAINT AQUA (-2950 -2425);
DISPLAY INVISIBLE (-2950 -2425);
FORCEADD UNIVERSAL_GND..1
(-3000 -3000);
FORCEPROP 3 LASTPIN (-3000 -2950) SIG_NAME GND\g
J 0
(-2990 -2940);
DISPLAY 0.659574 (-2990 -2940);
PAINT MONO (-2990 -2940);
DISPLAY INVISIBLE (-2990 -2940);
FORCEPROP 2 LAST CDS_LIB logical_power
J 0
(-3000 -3000);
PAINT MONO (-3000 -3000);
DISPLAY INVISIBLE (-3000 -3000);
FORCEPROP 1 LAST HDL_POWER GND
J 1
(-2975 -3075);
DISPLAY 0.872340 (-2975 -3075);
PAINT GREEN (-2975 -3075);
DISPLAY INVISIBLE (-2975 -3075);
FORCEPROP 1 LAST PATH I125
J 0
(-2925 -3000);
DISPLAY 0.872340 (-2925 -3000);
PAINT AQUA (-2925 -3000);
DISPLAY INVISIBLE (-2925 -3000);
FORCEADD Q_CAP..1
R 2
(-3000 -2775);
FORCEPROP 1 LAST PART_NUMBER CH4104K1B00
J 2
(-3050 -2925);
DISPLAY 0.510638 (-3050 -2925);
DISPLAY INVISIBLE (-3050 -2925);
FORCEPROP 1 LAST VALUE 0.1UF
J 2
(-3050 -2725);
DISPLAY 0.510638 (-3050 -2725);
FORCEPROP 1 LAST VOLTAGE 25V
J 2
(-3050 -2775);
DISPLAY 0.510638 (-3050 -2775);
FORCEPROP 1 LAST MATERIAL X7R
J 2
(-3050 -2875);
DISPLAY 0.510638 (-3050 -2875);
FORCEPROP 1 LAST TOLERANCE 10%
J 2
(-3050 -2825);
DISPLAY 0.510638 (-3050 -2825);
FORCEPROP 1 LAST PACK_TYPE 0402
J 2
(-3050 -2975);
DISPLAY 0.510638 (-3050 -2975);
FORCEPROP 1 LAST $LOCATION C1320
J 2
(-3050 -2675);
DISPLAY 0.978723 (-3050 -2675);
FORCEPROP 1 LASTPIN (-3000 -2675) $PN 1
J 2
(-3010 -2695);
DISPLAY 0.787234 (-3010 -2695);
FORCEPROP 1 LASTPIN (-3000 -2875) $PN 2
J 2
(-3010 -2895);
DISPLAY 0.787234 (-3010 -2895);
FORCEPROP 2 LAST CDS_LIB pure_quanta
J 0
(-3000 -2775);
PAINT MONO (-3000 -2775);
DISPLAY INVISIBLE (-3000 -2775);
FORCEPROP 1 LAST PATH I126
J 2
(-3050 -2625);
DISPLAY 0.978723 (-3050 -2625);
PAINT WHITE (-3050 -2625);
DISPLAY INVISIBLE (-3050 -2625);
FORCEPROP 2 LAST CDS_LOCATION C1320
J 0
(-3050 -2575);
DISPLAY 1.021277 (-3050 -2575);
DISPLAY INVISIBLE (-3050 -2575);
FORCEPROP 2 LAST $SEC 1
J 0
(-3050 -2575);
DISPLAY 0.680851 (-3050 -2575);
PAINT MONO (-3050 -2575);
DISPLAY INVISIBLE (-3050 -2575);
FORCEPROP 2 LAST CDS_SEC 1
J 0
(-3050 -2575);
DISPLAY 1.021277 (-3050 -2575);
DISPLAY INVISIBLE (-3050 -2575);
FORCEADD Q_OSC4P..1
(-2450 -3100);
FORCEPROP 1 LAST PART_NUMBER BF625000014
J 0
(-2625 -2920);
DISPLAY 0.723404 (-2625 -2920);
PAINT GREEN (-2625 -2920);
DISPLAY INVISIBLE (-2625 -2920);
FORCEPROP 1 LAST MATERIAL OSC
J 0
(-2625 -2965);
DISPLAY 0.723404 (-2625 -2965);
PAINT GREEN (-2625 -2965);
FORCEPROP 2 LAST VALUE 25MHZ
J 0
(-2625 -2825);
DISPLAY 1.021277 (-2625 -2825);
FORCEPROP 2 LAST PACK_TYPE SMLF
J 0
(-2625 -2775);
DISPLAY 1.021277 (-2625 -2775);
FORCEPROP 1 LAST $LOCATION OSC2
J 0
(-2625 -2870);
DISPLAY 0.723404 (-2625 -2870);
PAINT GREEN (-2625 -2870);
FORCEPROP 2 LASTPIN (-2125 -3175) $PN 2
J 0
(-2115 -3165);
DISPLAY 0.808511 (-2115 -3165);
FORCEPROP 2 LASTPIN (-2775 -3175) $PN 1
J 2
(-2785 -3165);
DISPLAY 0.808511 (-2785 -3165);
FORCEPROP 2 LASTPIN (-2125 -3025) $PN 3
J 0
(-2115 -3015);
DISPLAY 0.808511 (-2115 -3015);
FORCEPROP 2 LASTPIN (-2775 -3025) $PN 4
J 2
(-2785 -3015);
DISPLAY 0.808511 (-2785 -3015);
FORCEPROP 1 LAST NEEDS_NO_SIZE TRUE
J 0
(-2450 -3100);
DISPLAY 0.468085 (-2450 -3100);
PAINT GREEN (-2450 -3100);
DISPLAY INVISIBLE (-2450 -3100);
FORCEPROP 2 LAST CDS_LIB pure_quanta
J 0
(-2450 -3100);
PAINT MONO (-2450 -3100);
DISPLAY INVISIBLE (-2450 -3100);
FORCEPROP 1 LAST PATH I127
J 0
(-2300 -2965);
DISPLAY 0.723404 (-2300 -2965);
PAINT GREEN (-2300 -2965);
DISPLAY INVISIBLE (-2300 -2965);
FORCEPROP 2 LAST CDS_LOCATION OSC2
J 0
(-2625 -2725);
DISPLAY 1.021277 (-2625 -2725);
DISPLAY INVISIBLE (-2625 -2725);
FORCEPROP 2 LAST $SEC 1
J 0
(-2625 -2725);
DISPLAY 0.680851 (-2625 -2725);
PAINT MONO (-2625 -2725);
DISPLAY INVISIBLE (-2625 -2725);
FORCEPROP 2 LAST CDS_SEC 1
J 0
(-2625 -2725);
DISPLAY 1.021277 (-2625 -2725);
DISPLAY INVISIBLE (-2625 -2725);
FORCEADD UNIVERSAL_POWER..1
(-3725 -2725);
FORCEPROP 3 LASTPIN (-3725 -2775) SIG_NAME P3V3_AUX\g
J 0
(-3715 -2765);
DISPLAY 0.659574 (-3715 -2765);
PAINT MONO (-3715 -2765);
DISPLAY INVISIBLE (-3715 -2765);
FORCEPROP 1 LAST HDL_POWER P3V3_AUX
J 1
(-3725 -2675);
DISPLAY 0.872340 (-3725 -2675);
PAINT GREEN (-3725 -2675);
FORCEPROP 2 LAST CDS_LIB logical_power
J 0
(-3725 -2725);
PAINT MONO (-3725 -2725);
DISPLAY INVISIBLE (-3725 -2725);
FORCEPROP 1 LAST PATH I128
J 0
(-3675 -2700);
DISPLAY 0.872340 (-3675 -2700);
PAINT AQUA (-3675 -2700);
DISPLAY INVISIBLE (-3675 -2700);
FORCEADD Q_RES..2
R 2
(-3725 -2950);
FORCEPROP 1 LAST PART_NUMBER CS31002FB08
J 2
(-3765 -3075);
DISPLAY 0.638298 (-3765 -3075);
DISPLAY INVISIBLE (-3765 -3075);
FORCEPROP 1 LAST VALUE 10K
J 2
(-3770 -2875);
DISPLAY 0.638298 (-3770 -2875);
FORCEPROP 1 LAST TOLERANCE 1%
J 2
(-3770 -2925);
DISPLAY 0.638298 (-3770 -2925);
FORCEPROP 1 LAST WATTAGE 1/16W
J 2
(-3765 -2975);
DISPLAY 0.638298 (-3765 -2975);
FORCEPROP 1 LAST MATERIAL CHIP
J 2
(-3765 -3025);
DISPLAY 0.638298 (-3765 -3025);
FORCEPROP 1 LAST PACK_TYPE 0402LF
J 2
(-3765 -3125);
DISPLAY 0.638298 (-3765 -3125);
FORCEPROP 1 LAST $LOCATION R1099
J 2
(-3770 -2825);
DISPLAY 0.978723 (-3770 -2825);
FORCEPROP 1 LASTPIN (-3725 -2850) $PN 1
J 2
(-3730 -2888);
DISPLAY 0.787234 (-3730 -2888);
FORCEPROP 1 LASTPIN (-3725 -3050) $PN 2
J 2
(-3730 -3040);
DISPLAY 0.787234 (-3730 -3040);
FORCEPROP 2 LAST CDS_LIB pure_quanta
J 0
(-3725 -2950);
PAINT MONO (-3725 -2950);
DISPLAY INVISIBLE (-3725 -2950);
FORCEPROP 1 LAST PATH I129
J 2
(-3775 -2775);
DISPLAY 0.978723 (-3775 -2775);
PAINT WHITE (-3775 -2775);
DISPLAY INVISIBLE (-3775 -2775);
FORCEPROP 2 LAST CDS_LOCATION R1099
J 0
(-3775 -2725);
DISPLAY 1.021277 (-3775 -2725);
DISPLAY INVISIBLE (-3775 -2725);
FORCEPROP 2 LAST $SEC 1
J 0
(-3775 -2725);
DISPLAY 0.680851 (-3775 -2725);
PAINT MONO (-3775 -2725);
DISPLAY INVISIBLE (-3775 -2725);
FORCEPROP 2 LAST CDS_SEC 1
J 0
(-3775 -2725);
DISPLAY 1.021277 (-3775 -2725);
DISPLAY INVISIBLE (-3775 -2725);
FORCEADD OFFPAGE..1
R 2
(2400 1175);
FORCEPROP 2 LAST $XR1 119 
J 0
(2676 1175);
DISPLAY 0.638298 (2676 1175);
PAINT MONO (2676 1175);
FORCEPROP 2 LAST $XR0 13 
J 0
(2586 1175);
DISPLAY 0.638298 (2586 1175);
PAINT MONO (2586 1175);
FORCEPROP 2 LAST PATH I13
J 0
(2700 1225);
DISPLAY 1.021277 (2700 1225);
DISPLAY INVISIBLE (2700 1225);
FORCEPROP 2 LAST CDS_LIB standard
J 0
(2400 1175);
DISPLAY INVISIBLE (2400 1175);
FORCEPROP 1 LAST OFFPAGE TRUE
J 2
(2075 1050);
DISPLAY 1.170213 (2075 1050);
PAINT GREEN (2075 1050);
DISPLAY INVISIBLE (2075 1050);
FORCEPROP 1 LAST COMMENT_BODY TRUE
J 2
(2275 1075);
DISPLAY 1.170213 (2275 1075);
PAINT GREEN (2275 1075);
DISPLAY INVISIBLE (2275 1075);
FORCEADD OFFPAGE..1
(-1250 -25);
FORCEPROP 2 LAST $XR0 171 
J 0
(-1502 -25);
DISPLAY 0.638298 (-1502 -25);
PAINT MONO (-1502 -25);
FORCEPROP 2 LAST PATH I130
J 0
(-1525 25);
DISPLAY 1.021277 (-1525 25);
DISPLAY INVISIBLE (-1525 25);
FORCEPROP 1 LAST COMMENT_BODY TRUE
J 0
(-1125 -125);
DISPLAY 1.170213 (-1125 -125);
PAINT GREEN (-1125 -125);
DISPLAY INVISIBLE (-1125 -125);
FORCEPROP 1 LAST OFFPAGE TRUE
J 0
(-925 -150);
DISPLAY 0.872340 (-925 -150);
DISPLAY INVISIBLE (-925 -150);
FORCEPROP 2 LAST CDS_LIB standard
J 0
(-1250 -25);
DISPLAY INVISIBLE (-1250 -25);
FORCEADD OFFPAGE..1
(-1250 -75);
FORCEPROP 2 LAST $XR0 171 
J 0
(-1502 -75);
DISPLAY 0.638298 (-1502 -75);
PAINT MONO (-1502 -75);
FORCEPROP 2 LAST PATH I131
J 0
(-1500 -25);
DISPLAY 1.021277 (-1500 -25);
DISPLAY INVISIBLE (-1500 -25);
FORCEPROP 1 LAST COMMENT_BODY TRUE
J 0
(-1125 -175);
DISPLAY 1.170213 (-1125 -175);
PAINT GREEN (-1125 -175);
DISPLAY INVISIBLE (-1125 -175);
FORCEPROP 1 LAST OFFPAGE TRUE
J 0
(-925 -200);
DISPLAY 0.872340 (-925 -200);
DISPLAY INVISIBLE (-925 -200);
FORCEPROP 2 LAST CDS_LIB standard
J 0
(-1250 -75);
DISPLAY INVISIBLE (-1250 -75);
FORCEADD OFFPAGE..1
(-1250 -175);
FORCEPROP 2 LAST $XR0 172 
J 0
(-1502 -175);
DISPLAY 0.638298 (-1502 -175);
PAINT MONO (-1502 -175);
FORCEPROP 2 LAST CDS_LIB standard
J 2
(-1250 -175);
DISPLAY INVISIBLE (-1250 -175);
FORCEPROP 1 LAST OFFPAGE TRUE
J 0
(-925 -300);
DISPLAY 1.170213 (-925 -300);
PAINT GREEN (-925 -300);
DISPLAY INVISIBLE (-925 -300);
FORCEPROP 1 LAST COMMENT_BODY TRUE
J 0
(-1125 -275);
DISPLAY 1.170213 (-1125 -275);
PAINT GREEN (-1125 -275);
DISPLAY INVISIBLE (-1125 -275);
FORCEPROP 2 LAST PATH I133
J 0
(-1500 -125);
DISPLAY 1.021277 (-1500 -125);
DISPLAY INVISIBLE (-1500 -125);
FORCEADD OFFPAGE..1
(-1250 -225);
FORCEPROP 2 LAST $XR0 172 
J 0
(-1502 -225);
DISPLAY 0.638298 (-1502 -225);
PAINT MONO (-1502 -225);
FORCEPROP 1 LAST COMMENT_BODY TRUE
J 0
(-1125 -325);
DISPLAY 1.170213 (-1125 -325);
PAINT GREEN (-1125 -325);
DISPLAY INVISIBLE (-1125 -325);
FORCEPROP 1 LAST OFFPAGE TRUE
J 0
(-925 -350);
DISPLAY 0.872340 (-925 -350);
DISPLAY INVISIBLE (-925 -350);
FORCEPROP 2 LAST CDS_LIB standard
J 0
(-1250 -225);
PAINT MONO (-1250 -225);
DISPLAY INVISIBLE (-1250 -225);
FORCEPROP 2 LAST PATH I134
J 0
(-1500 -175);
DISPLAY 1.021277 (-1500 -175);
DISPLAY INVISIBLE (-1500 -175);
FORCEADD OFFPAGE..1
(-1250 -275);
FORCEPROP 2 LAST $XR0 172 
J 0
(-1502 -275);
DISPLAY 0.638298 (-1502 -275);
PAINT MONO (-1502 -275);
FORCEPROP 1 LAST OFFPAGE TRUE
J 0
(-925 -400);
DISPLAY 0.872340 (-925 -400);
DISPLAY INVISIBLE (-925 -400);
FORCEPROP 1 LAST COMMENT_BODY TRUE
J 0
(-1125 -375);
DISPLAY 1.170213 (-1125 -375);
PAINT GREEN (-1125 -375);
DISPLAY INVISIBLE (-1125 -375);
FORCEPROP 2 LAST CDS_LIB standard
J 0
(-1250 -275);
PAINT MONO (-1250 -275);
DISPLAY INVISIBLE (-1250 -275);
FORCEPROP 2 LAST PATH I135
J 0
(-1500 -225);
DISPLAY 1.021277 (-1500 -225);
DISPLAY INVISIBLE (-1500 -225);
FORCEADD OFFPAGE..1
R 2
(2400 1125);
FORCEPROP 2 LAST $XR1 119 
J 0
(2676 1125);
DISPLAY 0.638298 (2676 1125);
PAINT MONO (2676 1125);
FORCEPROP 2 LAST $XR0 13 
J 0
(2586 1125);
DISPLAY 0.638298 (2586 1125);
PAINT MONO (2586 1125);
FORCEPROP 2 LAST PATH I14
J 0
(2700 1175);
DISPLAY 1.021277 (2700 1175);
DISPLAY INVISIBLE (2700 1175);
FORCEPROP 2 LAST CDS_LIB standard
J 0
(2400 1125);
DISPLAY INVISIBLE (2400 1125);
FORCEPROP 1 LAST COMMENT_BODY TRUE
J 2
(2275 1025);
DISPLAY 1.170213 (2275 1025);
PAINT GREEN (2275 1025);
DISPLAY INVISIBLE (2275 1025);
FORCEPROP 1 LAST OFFPAGE TRUE
J 2
(2075 1000);
DISPLAY 1.170213 (2075 1000);
PAINT GREEN (2075 1000);
DISPLAY INVISIBLE (2075 1000);
FORCEADD OFFPAGE..1
(-1250 -525);
FORCEPROP 2 LAST $XR0 240 
J 0
(-1532 -525);
DISPLAY 0.638298 (-1532 -525);
PAINT MONO (-1532 -525);
FORCEPROP 1 LAST COMMENT_BODY TRUE
J 0
(-1125 -625);
DISPLAY 1.170213 (-1125 -625);
PAINT GREEN (-1125 -625);
DISPLAY INVISIBLE (-1125 -625);
FORCEPROP 1 LAST OFFPAGE TRUE
J 0
(-925 -650);
DISPLAY 0.872340 (-925 -650);
DISPLAY INVISIBLE (-925 -650);
FORCEPROP 2 LAST PATH I144
J 0
(-1500 -475);
DISPLAY 1.021277 (-1500 -475);
DISPLAY INVISIBLE (-1500 -475);
FORCEPROP 2 LAST CDS_LIB standard
J 0
(-1250 -525);
PAINT MONO (-1250 -525);
DISPLAY INVISIBLE (-1250 -525);
FORCEADD OFFPAGE..2
R 2
(-1250 -475);
FORCEPROP 2 LAST $XR0 240 
J 0
(-1535 -475);
DISPLAY 0.638298 (-1535 -475);
PAINT MONO (-1535 -475);
FORCEPROP 2 LAST CDS_LIB standard
J 0
(-1250 -475);
DISPLAY INVISIBLE (-1250 -475);
FORCEPROP 2 LAST PATH I145
J 0
(-1200 -400);
DISPLAY 1.021277 (-1200 -400);
DISPLAY INVISIBLE (-1200 -400);
FORCEPROP 1 LAST OFFPAGE TRUE
J 2
(-1575 -600);
DISPLAY 1.170213 (-1575 -600);
PAINT GREEN (-1575 -600);
DISPLAY INVISIBLE (-1575 -600);
FORCEPROP 1 LAST COMMENT_BODY TRUE
J 2
(-1205 -570);
DISPLAY 1.170213 (-1205 -570);
PAINT GREEN (-1205 -570);
DISPLAY INVISIBLE (-1205 -570);
FORCEADD OFFPAGE..2
R 2
(-1250 -425);
FORCEPROP 2 LAST $XR0 240 
J 0
(-1535 -425);
DISPLAY 0.638298 (-1535 -425);
PAINT MONO (-1535 -425);
FORCEPROP 2 LAST CDS_LIB standard
J 0
(-1250 -425);
DISPLAY INVISIBLE (-1250 -425);
FORCEPROP 2 LAST PATH I146
J 0
(-1200 -350);
DISPLAY 1.021277 (-1200 -350);
DISPLAY INVISIBLE (-1200 -350);
FORCEPROP 1 LAST COMMENT_BODY TRUE
J 2
(-1205 -520);
DISPLAY 1.170213 (-1205 -520);
PAINT GREEN (-1205 -520);
DISPLAY INVISIBLE (-1205 -520);
FORCEPROP 1 LAST OFFPAGE TRUE
J 2
(-1575 -550);
DISPLAY 1.170213 (-1575 -550);
PAINT GREEN (-1575 -550);
DISPLAY INVISIBLE (-1575 -550);
FORCEADD Q_RES..1
(2675 -2650);
FORCEPROP 1 LAST PART_NUMBER CS03322FB03
J 0
(2525 -2575);
DISPLAY 0.638298 (2525 -2575);
DISPLAY INVISIBLE (2525 -2575);
FORCEPROP 1 LAST VALUE 33.2
J 2
(2925 -2650);
DISPLAY 0.638298 (2925 -2650);
FORCEPROP 1 LAST TOLERANCE 1%
J 0
(2950 -2650);
DISPLAY 0.638298 (2950 -2650);
FORCEPROP 1 LAST MATERIAL CHIP
J 0
(3025 -2650);
DISPLAY 0.638298 (3025 -2650);
FORCEPROP 1 LAST WATTAGE 1/16W
J 2
(2875 -2525);
DISPLAY 0.638298 (2875 -2525);
FORCEPROP 1 LAST PACK_TYPE 0402LF
J 0
(2525 -2525);
DISPLAY 0.638298 (2525 -2525);
FORCEPROP 1 LAST $LOCATION R4259
J 0
(2375 -2650);
DISPLAY 0.638298 (2375 -2650);
FORCEPROP 1 LASTPIN (2575 -2650) $PN 1
J 0
(2587 -2638);
DISPLAY 0.787234 (2587 -2638);
PAINT MONO (2587 -2638);
FORCEPROP 1 LASTPIN (2775 -2650) $PN 2
J 0
(2737 -2638);
DISPLAY 0.787234 (2737 -2638);
PAINT MONO (2737 -2638);
FORCEPROP 2 LAST CDS_LIB pure_quanta
J 0
(2675 -2650);
DISPLAY INVISIBLE (2675 -2650);
FORCEPROP 1 LAST PATH I147
J 0
(2625 -2500);
DISPLAY 0.978723 (2625 -2500);
PAINT WHITE (2625 -2500);
DISPLAY INVISIBLE (2625 -2500);
FORCEPROP 0 LAST CDS_LOCATION R4259
J 0
(2875 -2475);
DISPLAY 1.021277 (2875 -2475);
DISPLAY INVISIBLE (2875 -2475);
FORCEPROP 0 LAST $SEC 1
J 0
(2875 -2475);
DISPLAY 0.680851 (2875 -2475);
PAINT MONO (2875 -2475);
DISPLAY INVISIBLE (2875 -2475);
FORCEPROP 0 LAST CDS_SEC 1
J 0
(2875 -2475);
DISPLAY 1.021277 (2875 -2475);
DISPLAY INVISIBLE (2875 -2475);
FORCEADD OFFPAGE..1
(1400 -2650);
FORCEPROP 2 LAST $XR0 170 
J 0
(1118 -2650);
DISPLAY 0.638298 (1118 -2650);
PAINT MONO (1118 -2650);
FORCEPROP 1 LAST OFFPAGE TRUE
J 0
(1725 -2775);
DISPLAY 0.872340 (1725 -2775);
DISPLAY INVISIBLE (1725 -2775);
FORCEPROP 1 LAST COMMENT_BODY TRUE
J 0
(1525 -2750);
DISPLAY 1.170213 (1525 -2750);
PAINT GREEN (1525 -2750);
DISPLAY INVISIBLE (1525 -2750);
FORCEPROP 2 LAST PATH I148
J 0
(1450 -2575);
DISPLAY 1.021277 (1450 -2575);
DISPLAY INVISIBLE (1450 -2575);
FORCEPROP 2 LAST CDS_LIB standard
J 0
(1400 -2650);
DISPLAY INVISIBLE (1400 -2650);
FORCEADD OFFPAGE..2
(4225 -2650);
FORCEPROP 2 LAST $XR0 214 
J 0
(4414 -2650);
DISPLAY 0.638298 (4414 -2650);
PAINT MONO (4414 -2650);
FORCEPROP 2 LAST CDS_LIB standard
J 0
(4225 -2650);
DISPLAY INVISIBLE (4225 -2650);
FORCEPROP 2 LAST PATH I149
J 0
(4400 -2575);
DISPLAY 1.021277 (4400 -2575);
DISPLAY INVISIBLE (4400 -2575);
FORCEPROP 1 LAST COMMENT_BODY TRUE
J 0
(4180 -2745);
DISPLAY 0.872340 (4180 -2745);
PAINT PEACH (4180 -2745);
DISPLAY INVISIBLE (4180 -2745);
FORCEPROP 1 LAST OFFPAGE TRUE
J 0
(4550 -2775);
DISPLAY 0.872340 (4550 -2775);
PAINT GREEN (4550 -2775);
DISPLAY INVISIBLE (4550 -2775);
FORCEADD OFFPAGE..1
R 2
(2400 1075);
FORCEPROP 2 LAST $XR1 119 
J 0
(2676 1075);
DISPLAY 0.638298 (2676 1075);
PAINT MONO (2676 1075);
FORCEPROP 2 LAST $XR0 13 
J 0
(2586 1075);
DISPLAY 0.638298 (2586 1075);
PAINT MONO (2586 1075);
FORCEPROP 2 LAST PATH I15
J 0
(2700 1125);
DISPLAY 1.021277 (2700 1125);
DISPLAY INVISIBLE (2700 1125);
FORCEPROP 1 LAST OFFPAGE TRUE
J 2
(2075 950);
DISPLAY 1.170213 (2075 950);
PAINT GREEN (2075 950);
DISPLAY INVISIBLE (2075 950);
FORCEPROP 1 LAST COMMENT_BODY TRUE
J 2
(2275 975);
DISPLAY 1.170213 (2275 975);
PAINT GREEN (2275 975);
DISPLAY INVISIBLE (2275 975);
FORCEPROP 2 LAST CDS_LIB standard
J 0
(2400 1075);
PAINT MONO (2400 1075);
DISPLAY INVISIBLE (2400 1075);
FORCEADD OFFPAGE..1
(-1250 -575);
FORCEPROP 2 LAST $XR0 214 
J 0
(-1502 -575);
DISPLAY 0.638298 (-1502 -575);
PAINT MONO (-1502 -575);
FORCEPROP 2 LAST CDS_LIB standard
J 0
(-1250 -575);
DISPLAY INVISIBLE (-1250 -575);
FORCEPROP 2 LAST PATH I150
J 0
(-1200 -500);
DISPLAY 1.021277 (-1200 -500);
DISPLAY INVISIBLE (-1200 -500);
FORCEPROP 1 LAST COMMENT_BODY TRUE
J 0
(-1125 -675);
DISPLAY 1.170213 (-1125 -675);
PAINT GREEN (-1125 -675);
DISPLAY INVISIBLE (-1125 -675);
FORCEPROP 1 LAST OFFPAGE TRUE
J 0
(-925 -700);
DISPLAY 0.872340 (-925 -700);
DISPLAY INVISIBLE (-925 -700);
FORCEADD OFFPAGE..1
R 2
(2400 -25);
FORCEPROP 2 LAST $XR0 153 
J 0
(2616 -25);
DISPLAY 0.638298 (2616 -25);
PAINT MONO (2616 -25);
FORCEPROP 2 LAST CDS_LIB standard
J 2
(2400 -25);
PAINT MONO (2400 -25);
DISPLAY INVISIBLE (2400 -25);
FORCEPROP 2 LAST PATH I155
J 2
(2650 25);
DISPLAY 1.021277 (2650 25);
DISPLAY INVISIBLE (2650 25);
FORCEPROP 1 LAST OFFPAGE TRUE
J 2
(2075 -150);
DISPLAY 0.872340 (2075 -150);
PAINT GREEN (2075 -150);
DISPLAY INVISIBLE (2075 -150);
FORCEPROP 1 LAST COMMENT_BODY TRUE
J 2
(2275 -125);
DISPLAY 0.872340 (2275 -125);
PAINT GREEN (2275 -125);
DISPLAY INVISIBLE (2275 -125);
FORCEADD OFFPAGE..1
R 2
(2400 -75);
FORCEPROP 2 LAST $XR0 159 
J 0
(2586 -75);
DISPLAY 0.638298 (2586 -75);
PAINT MONO (2586 -75);
FORCEPROP 2 LAST CDS_LIB standard
J 2
(2400 -75);
PAINT MONO (2400 -75);
DISPLAY INVISIBLE (2400 -75);
FORCEPROP 2 LAST PATH I156
J 0
(3025 -25);
DISPLAY 1.021277 (3025 -25);
DISPLAY INVISIBLE (3025 -25);
FORCEPROP 1 LAST COMMENT_BODY TRUE
J 2
(2275 -175);
DISPLAY 0.872340 (2275 -175);
PAINT GREEN (2275 -175);
DISPLAY INVISIBLE (2275 -175);
FORCEPROP 1 LAST OFFPAGE TRUE
J 2
(2075 -200);
DISPLAY 0.872340 (2075 -200);
PAINT GREEN (2075 -200);
DISPLAY INVISIBLE (2075 -200);
FORCEADD OFFPAGE..2
(4200 -1175);
FORCEPROP 2 LAST $XR0 214 
J 0
(4389 -1175);
DISPLAY 0.638298 (4389 -1175);
PAINT MONO (4389 -1175);
FORCEPROP 1 LAST OFFPAGE TRUE
J 0
(4525 -1300);
DISPLAY 1.170213 (4525 -1300);
PAINT GREEN (4525 -1300);
DISPLAY INVISIBLE (4525 -1300);
FORCEPROP 1 LAST COMMENT_BODY TRUE
J 0
(4155 -1270);
DISPLAY 1.170213 (4155 -1270);
PAINT GREEN (4155 -1270);
DISPLAY INVISIBLE (4155 -1270);
FORCEPROP 2 LAST CDS_LIB standard
J 0
(4200 -1175);
PAINT MONO (4200 -1175);
DISPLAY INVISIBLE (4200 -1175);
FORCEPROP 2 LAST PATH I157
J 0
(4525 -1125);
DISPLAY 1.021277 (4525 -1125);
DISPLAY INVISIBLE (4525 -1125);
FORCEADD OFFPAGE..2
(4200 -1000);
FORCEPROP 2 LAST $XR0 214 
J 0
(4389 -1000);
DISPLAY 0.638298 (4389 -1000);
PAINT MONO (4389 -1000);
FORCEPROP 2 LAST CDS_LIB standard
J 0
(4200 -1000);
PAINT MONO (4200 -1000);
DISPLAY INVISIBLE (4200 -1000);
FORCEPROP 1 LAST OFFPAGE TRUE
J 0
(4525 -1125);
DISPLAY 1.170213 (4525 -1125);
PAINT GREEN (4525 -1125);
DISPLAY INVISIBLE (4525 -1125);
FORCEPROP 1 LAST COMMENT_BODY TRUE
J 0
(4155 -1095);
DISPLAY 1.170213 (4155 -1095);
PAINT GREEN (4155 -1095);
DISPLAY INVISIBLE (4155 -1095);
FORCEPROP 2 LAST PATH I158
J 0
(4525 -950);
DISPLAY 1.021277 (4525 -950);
DISPLAY INVISIBLE (4525 -950);
FORCEADD Q_RES..1
(2700 -1000);
FORCEPROP 1 LAST PART_NUMBER CS00002JB13
J 0
(2650 -950);
DISPLAY 0.404255 (2650 -950);
DISPLAY INVISIBLE (2650 -950);
FORCEPROP 1 LAST TOLERANCE 5%
J 0
(2875 -1000);
DISPLAY 0.510638 (2875 -1000);
FORCEPROP 1 LAST VALUE 0
J 2
(2850 -1000);
DISPLAY 0.510638 (2850 -1000);
FORCEPROP 1 LAST MATERIAL CHIP
J 0
(2650 -925);
DISPLAY 0.404255 (2650 -925);
FORCEPROP 1 LAST PACK_TYPE 0402LF
J 0
(2650 -900);
DISPLAY 0.404255 (2650 -900);
FORCEPROP 1 LAST WATTAGE 1/16W
J 2
(2875 -925);
DISPLAY 0.404255 (2875 -925);
FORCEPROP 1 LAST $LOCATION R4599
J 0
(2475 -1000);
DISPLAY 0.638298 (2475 -1000);
FORCEPROP 1 LASTPIN (2600 -1000) $PN 1
J 0
(2612 -988);
DISPLAY 0.787234 (2612 -988);
FORCEPROP 1 LASTPIN (2800 -1000) $PN 2
J 0
(2762 -988);
DISPLAY 0.787234 (2762 -988);
FORCEPROP 2 LAST CDS_LIB pure_quanta
J 0
(2700 -1000);
PAINT MONO (2700 -1000);
DISPLAY INVISIBLE (2700 -1000);
FORCEPROP 1 LAST PATH I159
J 0
(2650 -850);
DISPLAY 0.978723 (2650 -850);
PAINT WHITE (2650 -850);
DISPLAY INVISIBLE (2650 -850);
FORCEPROP 2 LAST CDS_LOCATION R4599
J 0
(2650 -800);
DISPLAY 1.021277 (2650 -800);
DISPLAY INVISIBLE (2650 -800);
FORCEPROP 2 LAST $SEC 1
J 0
(2650 -800);
DISPLAY 0.680851 (2650 -800);
PAINT MONO (2650 -800);
DISPLAY INVISIBLE (2650 -800);
FORCEPROP 2 LAST CDS_SEC 1
J 0
(2650 -800);
DISPLAY 1.021277 (2650 -800);
DISPLAY INVISIBLE (2650 -800);
FORCEADD OFFPAGE..1
R 2
(2400 1025);
FORCEPROP 2 LAST $XR1 119 
J 0
(2676 1025);
DISPLAY 0.638298 (2676 1025);
PAINT MONO (2676 1025);
FORCEPROP 2 LAST $XR0 44 
J 0
(2586 1025);
DISPLAY 0.638298 (2586 1025);
PAINT MONO (2586 1025);
FORCEPROP 2 LAST PATH I16
J 0
(2700 1075);
DISPLAY 1.021277 (2700 1075);
DISPLAY INVISIBLE (2700 1075);
FORCEPROP 1 LAST COMMENT_BODY TRUE
J 2
(2275 925);
DISPLAY 1.170213 (2275 925);
PAINT GREEN (2275 925);
DISPLAY INVISIBLE (2275 925);
FORCEPROP 1 LAST OFFPAGE TRUE
J 2
(2075 900);
DISPLAY 1.170213 (2075 900);
PAINT GREEN (2075 900);
DISPLAY INVISIBLE (2075 900);
FORCEPROP 2 LAST CDS_LIB standard
J 0
(2400 1025);
DISPLAY INVISIBLE (2400 1025);
FORCEADD Q_RES..1
(2700 -1175);
FORCEPROP 1 LAST PART_NUMBER CS00002JB13
J 0
(2650 -1125);
DISPLAY 0.404255 (2650 -1125);
DISPLAY INVISIBLE (2650 -1125);
FORCEPROP 1 LAST TOLERANCE 5%
J 0
(2875 -1175);
DISPLAY 0.510638 (2875 -1175);
FORCEPROP 1 LAST VALUE 0
J 2
(2850 -1175);
DISPLAY 0.510638 (2850 -1175);
FORCEPROP 1 LAST MATERIAL CHIP
J 0
(2650 -1100);
DISPLAY 0.404255 (2650 -1100);
FORCEPROP 1 LAST WATTAGE 1/16W
J 2
(2875 -1100);
DISPLAY 0.404255 (2875 -1100);
FORCEPROP 1 LAST PACK_TYPE 0402LF
J 0
(2650 -1075);
DISPLAY 0.404255 (2650 -1075);
FORCEPROP 1 LAST $LOCATION R4600
J 0
(2475 -1175);
DISPLAY 0.510638 (2475 -1175);
FORCEPROP 1 LASTPIN (2600 -1175) $PN 1
J 0
(2612 -1163);
DISPLAY 0.787234 (2612 -1163);
PAINT MONO (2612 -1163);
FORCEPROP 1 LASTPIN (2800 -1175) $PN 2
J 0
(2762 -1163);
DISPLAY 0.787234 (2762 -1163);
PAINT MONO (2762 -1163);
FORCEPROP 2 LAST CDS_LIB pure_quanta
J 0
(2700 -1175);
DISPLAY INVISIBLE (2700 -1175);
FORCEPROP 1 LAST PATH I160
J 0
(2650 -1025);
DISPLAY 0.978723 (2650 -1025);
PAINT WHITE (2650 -1025);
DISPLAY INVISIBLE (2650 -1025);
FORCEPROP 0 LAST CDS_LOCATION R4600
J 0
(2650 -1050);
DISPLAY 1.021277 (2650 -1050);
DISPLAY INVISIBLE (2650 -1050);
FORCEPROP 0 LAST $SEC 1
J 0
(2650 -1050);
DISPLAY 0.680851 (2650 -1050);
PAINT MONO (2650 -1050);
DISPLAY INVISIBLE (2650 -1050);
FORCEPROP 0 LAST CDS_SEC 1
J 0
(2650 -1050);
DISPLAY 1.021277 (2650 -1050);
DISPLAY INVISIBLE (2650 -1050);
FORCEADD OFFPAGE..1
(1400 -1000);
FORCEPROP 2 LAST $XR2 164 
J 0
(878 -1000);
DISPLAY 0.638298 (878 -1000);
PAINT MONO (878 -1000);
FORCEPROP 2 LAST $XR1 163 
J 0
(998 -1000);
DISPLAY 0.638298 (998 -1000);
PAINT MONO (998 -1000);
FORCEPROP 2 LAST $XR0 162 
J 0
(1118 -1000);
DISPLAY 0.638298 (1118 -1000);
PAINT MONO (1118 -1000);
FORCEPROP 1 LAST COMMENT_BODY TRUE
J 0
(1525 -1100);
DISPLAY 1.170213 (1525 -1100);
PAINT GREEN (1525 -1100);
DISPLAY INVISIBLE (1525 -1100);
FORCEPROP 1 LAST OFFPAGE TRUE
J 0
(1725 -1125);
DISPLAY 0.872340 (1725 -1125);
DISPLAY INVISIBLE (1725 -1125);
FORCEPROP 2 LAST CDS_LIB standard
J 0
(1400 -1000);
PAINT MONO (1400 -1000);
DISPLAY INVISIBLE (1400 -1000);
FORCEPROP 2 LAST PATH I161
J 0
(1125 -950);
DISPLAY 1.021277 (1125 -950);
DISPLAY INVISIBLE (1125 -950);
FORCEADD OFFPAGE..1
(1400 -1175);
FORCEPROP 2 LAST $XR2 158 
J 0
(878 -1175);
DISPLAY 0.638298 (878 -1175);
PAINT MONO (878 -1175);
FORCEPROP 2 LAST $XR1 157 
J 0
(998 -1175);
DISPLAY 0.638298 (998 -1175);
PAINT MONO (998 -1175);
FORCEPROP 2 LAST $XR0 156 
J 0
(1118 -1175);
DISPLAY 0.638298 (1118 -1175);
PAINT MONO (1118 -1175);
FORCEPROP 1 LAST COMMENT_BODY TRUE
J 0
(1525 -1275);
DISPLAY 1.170213 (1525 -1275);
PAINT GREEN (1525 -1275);
DISPLAY INVISIBLE (1525 -1275);
FORCEPROP 1 LAST OFFPAGE TRUE
J 0
(1725 -1300);
DISPLAY 0.872340 (1725 -1300);
DISPLAY INVISIBLE (1725 -1300);
FORCEPROP 2 LAST CDS_LIB standard
J 0
(1400 -1175);
PAINT MONO (1400 -1175);
DISPLAY INVISIBLE (1400 -1175);
FORCEPROP 2 LAST PATH I162
J 0
(1125 -1125);
DISPLAY 1.021277 (1125 -1125);
DISPLAY INVISIBLE (1125 -1125);
FORCEADD OFFPAGE..1
R 2
(2400 -175);
FORCEPROP 2 LAST $XR0 214 
J 0
(2586 -175);
DISPLAY 0.638298 (2586 -175);
PAINT MONO (2586 -175);
FORCEPROP 1 LAST OFFPAGE TRUE
J 2
(2075 -300);
DISPLAY 0.872340 (2075 -300);
PAINT GREEN (2075 -300);
DISPLAY INVISIBLE (2075 -300);
FORCEPROP 1 LAST COMMENT_BODY TRUE
J 2
(2275 -275);
DISPLAY 0.872340 (2275 -275);
PAINT GREEN (2275 -275);
DISPLAY INVISIBLE (2275 -275);
FORCEPROP 2 LAST PATH I163
J 0
(2575 -100);
DISPLAY 1.021277 (2575 -100);
DISPLAY INVISIBLE (2575 -100);
FORCEPROP 2 LAST CDS_LIB standard
J 0
(2400 -175);
DISPLAY INVISIBLE (2400 -175);
FORCEADD OFFPAGE..1
R 2
(2400 -125);
FORCEPROP 2 LAST $XR0 214 
J 0
(2586 -125);
DISPLAY 0.638298 (2586 -125);
PAINT MONO (2586 -125);
FORCEPROP 1 LAST COMMENT_BODY TRUE
J 2
(2275 -225);
DISPLAY 0.872340 (2275 -225);
PAINT GREEN (2275 -225);
DISPLAY INVISIBLE (2275 -225);
FORCEPROP 1 LAST OFFPAGE TRUE
J 2
(2075 -250);
DISPLAY 0.872340 (2075 -250);
PAINT GREEN (2075 -250);
DISPLAY INVISIBLE (2075 -250);
FORCEPROP 2 LAST PATH I164
J 0
(2575 -50);
DISPLAY 1.021277 (2575 -50);
DISPLAY INVISIBLE (2575 -50);
FORCEPROP 2 LAST CDS_LIB standard
J 0
(2400 -125);
DISPLAY INVISIBLE (2400 -125);
FORCEADD OFFPAGE..2
(4225 -2850);
FORCEPROP 2 LAST $XR0 239 
J 0
(4414 -2850);
DISPLAY 0.638298 (4414 -2850);
PAINT MONO (4414 -2850);
FORCEPROP 2 LAST PATH I165
J 0
(4425 -2800);
DISPLAY 1.021277 (4425 -2800);
DISPLAY INVISIBLE (4425 -2800);
FORCEPROP 2 LAST CDS_LIB standard
J 0
(4225 -2850);
DISPLAY INVISIBLE (4225 -2850);
FORCEPROP 1 LAST OFFPAGE TRUE
J 0
(4550 -2975);
DISPLAY 0.872340 (4550 -2975);
PAINT GREEN (4550 -2975);
DISPLAY INVISIBLE (4550 -2975);
FORCEPROP 1 LAST COMMENT_BODY TRUE
J 0
(4180 -2945);
DISPLAY 0.872340 (4180 -2945);
PAINT PEACH (4180 -2945);
DISPLAY INVISIBLE (4180 -2945);
FORCEADD Q_RES..1
(2675 -2950);
FORCEPROP 1 LAST PART_NUMBER CS00002JB13
J 0
(2525 -2900);
DISPLAY 0.404255 (2525 -2900);
DISPLAY INVISIBLE (2525 -2900);
FORCEPROP 1 LAST VALUE 0
J 2
(2825 -2950);
DISPLAY 0.510638 (2825 -2950);
FORCEPROP 1 LAST TOLERANCE 5%
J 0
(2850 -2950);
DISPLAY 0.510638 (2850 -2950);
FORCEPROP 1 LAST MATERIAL CHIP
J 0
(2925 -2950);
DISPLAY 0.510638 (2925 -2950);
FORCEPROP 1 LAST $LOCATION R4088
J 0
(2475 -2950);
DISPLAY 0.638298 (2475 -2950);
FORCEPROP 1 LASTPIN (2575 -2950) $PN 1
J 0
(2587 -2938);
DISPLAY 0.787234 (2587 -2938);
PAINT MONO (2587 -2938);
FORCEPROP 1 LASTPIN (2775 -2950) $PN 2
J 0
(2737 -2938);
DISPLAY 0.787234 (2737 -2938);
PAINT MONO (2737 -2938);
FORCEPROP 1 LAST PATH I166
J 0
(2625 -2800);
DISPLAY 0.978723 (2625 -2800);
PAINT WHITE (2625 -2800);
DISPLAY INVISIBLE (2625 -2800);
FORCEPROP 1 LAST WATTAGE 1/16W
J 2
(2825 -2850);
DISPLAY 0.510638 (2825 -2850);
DISPLAY INVISIBLE (2825 -2850);
FORCEPROP 1 LAST PACK_TYPE 0402LF
J 0
(2525 -2850);
DISPLAY 0.510638 (2525 -2850);
DISPLAY INVISIBLE (2525 -2850);
FORCEPROP 2 LAST CDS_LIB pure_quanta
J 0
(2675 -2950);
DISPLAY INVISIBLE (2675 -2950);
FORCEPROP 0 LAST CDS_LOCATION R4088
J 0
(2500 -2900);
DISPLAY 1.021277 (2500 -2900);
DISPLAY INVISIBLE (2500 -2900);
FORCEPROP 0 LAST $SEC 1
J 0
(2500 -2900);
DISPLAY 0.680851 (2500 -2900);
PAINT MONO (2500 -2900);
DISPLAY INVISIBLE (2500 -2900);
FORCEPROP 0 LAST CDS_SEC 1
J 0
(2500 -2900);
DISPLAY 1.021277 (2500 -2900);
DISPLAY INVISIBLE (2500 -2900);
FORCEADD Q_RES..1
(2675 -2850);
FORCEPROP 1 LAST PART_NUMBER CS00002JB13
J 0
(2525 -2800);
DISPLAY 0.510638 (2525 -2800);
DISPLAY INVISIBLE (2525 -2800);
FORCEPROP 1 LAST VALUE 0
J 2
(2825 -2850);
DISPLAY 0.510638 (2825 -2850);
FORCEPROP 1 LAST TOLERANCE 5%
J 0
(2850 -2850);
DISPLAY 0.510638 (2850 -2850);
FORCEPROP 1 LAST MATERIAL EMPTY
J 0
(2925 -2850);
DISPLAY 0.510638 (2925 -2850);
PAINT RED (2925 -2850);
FORCEPROP 1 LAST $LOCATION R1833
J 0
(2475 -2850);
DISPLAY 0.510638 (2475 -2850);
FORCEPROP 1 LASTPIN (2575 -2850) $PN 1
J 0
(2587 -2838);
DISPLAY 0.787234 (2587 -2838);
FORCEPROP 1 LASTPIN (2775 -2850) $PN 2
J 0
(2737 -2838);
DISPLAY 0.787234 (2737 -2838);
FORCEPROP 1 LAST PATH I167
J 0
(2625 -2700);
DISPLAY 0.978723 (2625 -2700);
PAINT WHITE (2625 -2700);
DISPLAY INVISIBLE (2625 -2700);
FORCEPROP 2 LAST CDS_LIB pure_quanta
J 0
(2675 -2850);
PAINT MONO (2675 -2850);
DISPLAY INVISIBLE (2675 -2850);
FORCEPROP 1 LAST WATTAGE 1/16W
J 2
(2825 -2750);
DISPLAY 0.510638 (2825 -2750);
DISPLAY INVISIBLE (2825 -2750);
FORCEPROP 1 LAST PACK_TYPE 0402LF
J 0
(2525 -2750);
DISPLAY 0.510638 (2525 -2750);
DISPLAY INVISIBLE (2525 -2750);
FORCEPROP 2 LAST CDS_LOCATION R1833
J 0
(2625 -2650);
DISPLAY 1.021277 (2625 -2650);
DISPLAY INVISIBLE (2625 -2650);
FORCEPROP 2 LAST $SEC 1
J 0
(2625 -2650);
DISPLAY 0.680851 (2625 -2650);
PAINT MONO (2625 -2650);
DISPLAY INVISIBLE (2625 -2650);
FORCEPROP 2 LAST CDS_SEC 1
J 0
(2625 -2650);
DISPLAY 1.021277 (2625 -2650);
DISPLAY INVISIBLE (2625 -2650);
FORCEADD OFFPAGE..1
(1400 -2850);
FORCEPROP 2 LAST $XR0 214 
J 0
(1118 -2850);
DISPLAY 0.638298 (1118 -2850);
PAINT MONO (1118 -2850);
FORCEPROP 2 LAST PATH I168
J 0
(1125 -2800);
DISPLAY 1.021277 (1125 -2800);
DISPLAY INVISIBLE (1125 -2800);
FORCEPROP 1 LAST OFFPAGE TRUE
J 0
(1725 -2975);
DISPLAY 0.872340 (1725 -2975);
DISPLAY INVISIBLE (1725 -2975);
FORCEPROP 1 LAST COMMENT_BODY TRUE
J 0
(1525 -2950);
DISPLAY 1.170213 (1525 -2950);
PAINT GREEN (1525 -2950);
DISPLAY INVISIBLE (1525 -2950);
FORCEPROP 2 LAST CDS_LIB standard
J 0
(1400 -2850);
DISPLAY INVISIBLE (1400 -2850);
FORCEADD OFFPAGE..1
(1400 -2950);
FORCEPROP 2 LAST $XR0 240 
J 0
(1118 -2950);
DISPLAY 0.638298 (1118 -2950);
PAINT MONO (1118 -2950);
FORCEPROP 2 LAST PATH I169
J 0
(1125 -2900);
DISPLAY 1.021277 (1125 -2900);
DISPLAY INVISIBLE (1125 -2900);
FORCEPROP 1 LAST OFFPAGE TRUE
J 0
(1725 -3075);
DISPLAY 0.872340 (1725 -3075);
DISPLAY INVISIBLE (1725 -3075);
FORCEPROP 1 LAST COMMENT_BODY TRUE
J 0
(1525 -3050);
DISPLAY 1.170213 (1525 -3050);
PAINT GREEN (1525 -3050);
DISPLAY INVISIBLE (1525 -3050);
FORCEPROP 2 LAST CDS_LIB standard
J 0
(1400 -2950);
DISPLAY INVISIBLE (1400 -2950);
FORCEADD OFFPAGE..1
R 2
(2400 975);
FORCEPROP 2 LAST $XR1 119 
J 0
(2676 975);
DISPLAY 0.638298 (2676 975);
PAINT MONO (2676 975);
FORCEPROP 2 LAST $XR0 44 
J 0
(2586 975);
DISPLAY 0.638298 (2586 975);
PAINT MONO (2586 975);
FORCEPROP 2 LAST PATH I17
J 0
(2700 1025);
DISPLAY 1.021277 (2700 1025);
DISPLAY INVISIBLE (2700 1025);
FORCEPROP 2 LAST CDS_LIB standard
J 0
(2400 975);
DISPLAY INVISIBLE (2400 975);
FORCEPROP 1 LAST OFFPAGE TRUE
J 2
(2075 850);
DISPLAY 1.170213 (2075 850);
PAINT GREEN (2075 850);
DISPLAY INVISIBLE (2075 850);
FORCEPROP 1 LAST COMMENT_BODY TRUE
J 2
(2275 875);
DISPLAY 1.170213 (2275 875);
PAINT GREEN (2275 875);
DISPLAY INVISIBLE (2275 875);
FORCEADD OFFPAGE..1
R 2
(2400 -275);
FORCEPROP 2 LAST $XR0 214 
J 0
(2586 -275);
DISPLAY 0.638298 (2586 -275);
PAINT MONO (2586 -275);
FORCEPROP 2 LAST CDS_LIB standard
J 2
(2400 -275);
DISPLAY INVISIBLE (2400 -275);
FORCEPROP 2 LAST PATH I170
J 0
(2600 -225);
DISPLAY 1.021277 (2600 -225);
DISPLAY INVISIBLE (2600 -225);
FORCEPROP 1 LAST COMMENT_BODY TRUE
J 2
(2275 -375);
DISPLAY 0.872340 (2275 -375);
PAINT GREEN (2275 -375);
DISPLAY INVISIBLE (2275 -375);
FORCEPROP 1 LAST OFFPAGE TRUE
J 2
(2075 -400);
DISPLAY 0.872340 (2075 -400);
PAINT GREEN (2075 -400);
DISPLAY INVISIBLE (2075 -400);
FORCEADD OFFPAGE..1
R 2
(2400 -225);
FORCEPROP 2 LAST $XR0 214 
J 0
(2586 -225);
DISPLAY 0.638298 (2586 -225);
PAINT MONO (2586 -225);
FORCEPROP 1 LAST COMMENT_BODY TRUE
J 2
(2275 -325);
DISPLAY 0.872340 (2275 -325);
PAINT GREEN (2275 -325);
DISPLAY INVISIBLE (2275 -325);
FORCEPROP 1 LAST OFFPAGE TRUE
J 2
(2075 -350);
DISPLAY 0.872340 (2075 -350);
PAINT GREEN (2075 -350);
DISPLAY INVISIBLE (2075 -350);
FORCEPROP 2 LAST CDS_LIB standard
J 2
(2400 -225);
DISPLAY INVISIBLE (2400 -225);
FORCEPROP 2 LAST PATH I171
J 0
(2600 -175);
DISPLAY 1.021277 (2600 -175);
DISPLAY INVISIBLE (2600 -175);
FORCEADD OFFPAGE..1
(-2250 -1200);
FORCEPROP 2 LAST $XR0 148 
J 0
(-2502 -1200);
DISPLAY 0.638298 (-2502 -1200);
PAINT MONO (-2502 -1200);
FORCEPROP 2 LAST CDS_LIB standard
J 0
(-2250 -1200);
DISPLAY INVISIBLE (-2250 -1200);
FORCEPROP 1 LAST COMMENT_BODY TRUE
J 0
(-2125 -1300);
DISPLAY 1.170213 (-2125 -1300);
PAINT GREEN (-2125 -1300);
DISPLAY INVISIBLE (-2125 -1300);
FORCEPROP 1 LAST OFFPAGE TRUE
J 0
(-1925 -1325);
DISPLAY 0.872340 (-1925 -1325);
DISPLAY INVISIBLE (-1925 -1325);
FORCEPROP 2 LAST PATH I172
J 0
(-2525 -1150);
DISPLAY 1.021277 (-2525 -1150);
DISPLAY INVISIBLE (-2525 -1150);
FORCEADD OFFPAGE..2
(250 -1200);
FORCEPROP 2 LAST $XR0 214 
J 0
(439 -1200);
DISPLAY 0.638298 (439 -1200);
PAINT MONO (439 -1200);
FORCEPROP 2 LAST CDS_LIB standard
J 0
(250 -1200);
PAINT MONO (250 -1200);
DISPLAY INVISIBLE (250 -1200);
FORCEPROP 1 LAST OFFPAGE TRUE
J 0
(575 -1325);
DISPLAY 0.872340 (575 -1325);
PAINT GREEN (575 -1325);
DISPLAY INVISIBLE (575 -1325);
FORCEPROP 1 LAST COMMENT_BODY TRUE
J 0
(205 -1295);
DISPLAY 0.872340 (205 -1295);
PAINT PEACH (205 -1295);
DISPLAY INVISIBLE (205 -1295);
FORCEPROP 2 LAST PATH I173
J 0
(450 -1150);
DISPLAY 1.021277 (450 -1150);
DISPLAY INVISIBLE (450 -1150);
FORCEADD OFFPAGE..2
(250 -1000);
FORCEPROP 2 LAST $XR0 214 
J 0
(439 -1000);
DISPLAY 0.638298 (439 -1000);
PAINT MONO (439 -1000);
FORCEPROP 2 LAST PATH I174
J 0
(450 -950);
DISPLAY 1.021277 (450 -950);
DISPLAY INVISIBLE (450 -950);
FORCEPROP 2 LAST CDS_LIB standard
J 0
(250 -1000);
PAINT MONO (250 -1000);
DISPLAY INVISIBLE (250 -1000);
FORCEPROP 1 LAST OFFPAGE TRUE
J 0
(575 -1125);
DISPLAY 0.872340 (575 -1125);
PAINT GREEN (575 -1125);
DISPLAY INVISIBLE (575 -1125);
FORCEPROP 1 LAST COMMENT_BODY TRUE
J 0
(205 -1095);
DISPLAY 0.872340 (205 -1095);
PAINT PEACH (205 -1095);
DISPLAY INVISIBLE (205 -1095);
FORCEADD Q_RES..1
(-1025 -1000);
FORCEPROP 1 LAST PART_NUMBER CS00002JB13
J 0
(-1075 -950);
DISPLAY 0.404255 (-1075 -950);
DISPLAY INVISIBLE (-1075 -950);
FORCEPROP 1 LAST TOLERANCE 5%
J 0
(-850 -1000);
DISPLAY 0.510638 (-850 -1000);
FORCEPROP 1 LAST VALUE 0
J 2
(-875 -1000);
DISPLAY 0.510638 (-875 -1000);
FORCEPROP 1 LAST MATERIAL CHIP
J 0
(-775 -1000);
DISPLAY 0.510638 (-775 -1000);
FORCEPROP 1 LAST $LOCATION R3066
J 0
(-1225 -1000);
DISPLAY 0.638298 (-1225 -1000);
FORCEPROP 1 LASTPIN (-1125 -1000) $PN 1
J 0
(-1113 -988);
DISPLAY 0.787234 (-1113 -988);
PAINT MONO (-1113 -988);
FORCEPROP 1 LASTPIN (-925 -1000) $PN 2
J 0
(-963 -988);
DISPLAY 0.787234 (-963 -988);
PAINT MONO (-963 -988);
FORCEPROP 1 LAST PATH I175
J 0
(-1075 -850);
DISPLAY 0.978723 (-1075 -850);
PAINT WHITE (-1075 -850);
DISPLAY INVISIBLE (-1075 -850);
FORCEPROP 1 LAST WATTAGE 1/16W
J 2
(-850 -925);
DISPLAY 0.404255 (-850 -925);
DISPLAY INVISIBLE (-850 -925);
FORCEPROP 1 LAST PACK_TYPE 0402LF
J 0
(-775 -1000);
DISPLAY 0.510638 (-775 -1000);
DISPLAY INVISIBLE (-775 -1000);
FORCEPROP 2 LAST CDS_LIB pure_quanta
J 0
(-1025 -1000);
DISPLAY INVISIBLE (-1025 -1000);
FORCEPROP 0 LAST CDS_LOCATION R3066
J 0
(-1225 -950);
DISPLAY 1.021277 (-1225 -950);
DISPLAY INVISIBLE (-1225 -950);
FORCEPROP 0 LAST $SEC 1
J 0
(-1225 -950);
DISPLAY 0.680851 (-1225 -950);
PAINT MONO (-1225 -950);
DISPLAY INVISIBLE (-1225 -950);
FORCEPROP 0 LAST CDS_SEC 1
J 0
(-1225 -950);
DISPLAY 1.021277 (-1225 -950);
DISPLAY INVISIBLE (-1225 -950);
FORCEADD Q_RES..1
(-1025 -1200);
FORCEPROP 1 LAST PART_NUMBER CS00002JB13
J 0
(-1075 -1150);
DISPLAY 0.404255 (-1075 -1150);
DISPLAY INVISIBLE (-1075 -1150);
FORCEPROP 1 LAST MATERIAL CHIP
J 0
(-775 -1200);
DISPLAY 0.510638 (-775 -1200);
FORCEPROP 1 LAST TOLERANCE 5%
J 0
(-850 -1200);
DISPLAY 0.510638 (-850 -1200);
FORCEPROP 1 LAST VALUE 0
J 2
(-875 -1200);
DISPLAY 0.510638 (-875 -1200);
FORCEPROP 1 LAST $LOCATION R3067
J 0
(-1225 -1200);
DISPLAY 0.510638 (-1225 -1200);
FORCEPROP 1 LASTPIN (-1125 -1200) $PN 1
J 0
(-1113 -1188);
DISPLAY 0.787234 (-1113 -1188);
PAINT MONO (-1113 -1188);
FORCEPROP 1 LASTPIN (-925 -1200) $PN 2
J 0
(-963 -1188);
DISPLAY 0.787234 (-963 -1188);
PAINT MONO (-963 -1188);
FORCEPROP 1 LAST WATTAGE 1/16W
J 2
(-850 -1125);
DISPLAY 0.404255 (-850 -1125);
DISPLAY INVISIBLE (-850 -1125);
FORCEPROP 1 LAST PACK_TYPE 0402LF
J 0
(-775 -1200);
DISPLAY 0.510638 (-775 -1200);
DISPLAY INVISIBLE (-775 -1200);
FORCEPROP 2 LAST CDS_LIB pure_quanta
J 0
(-1025 -1200);
DISPLAY INVISIBLE (-1025 -1200);
FORCEPROP 1 LAST PATH I176
J 0
(-1075 -1050);
DISPLAY 0.978723 (-1075 -1050);
PAINT WHITE (-1075 -1050);
DISPLAY INVISIBLE (-1075 -1050);
FORCEPROP 0 LAST CDS_LOCATION R3067
J 0
(-1225 -1150);
DISPLAY 1.021277 (-1225 -1150);
DISPLAY INVISIBLE (-1225 -1150);
FORCEPROP 0 LAST $SEC 1
J 0
(-1225 -1150);
DISPLAY 0.680851 (-1225 -1150);
PAINT MONO (-1225 -1150);
DISPLAY INVISIBLE (-1225 -1150);
FORCEPROP 0 LAST CDS_SEC 1
J 0
(-1225 -1150);
DISPLAY 1.021277 (-1225 -1150);
DISPLAY INVISIBLE (-1225 -1150);
FORCEADD OFFPAGE..1
(-2250 -1000);
FORCEPROP 2 LAST $XR0 148 
J 0
(-2502 -1000);
DISPLAY 0.638298 (-2502 -1000);
PAINT MONO (-2502 -1000);
FORCEPROP 2 LAST PATH I177
J 0
(-2525 -950);
DISPLAY 1.021277 (-2525 -950);
DISPLAY INVISIBLE (-2525 -950);
FORCEPROP 1 LAST OFFPAGE TRUE
J 0
(-1925 -1125);
DISPLAY 0.872340 (-1925 -1125);
DISPLAY INVISIBLE (-1925 -1125);
FORCEPROP 1 LAST COMMENT_BODY TRUE
J 0
(-2125 -1100);
DISPLAY 1.170213 (-2125 -1100);
PAINT GREEN (-2125 -1100);
DISPLAY INVISIBLE (-2125 -1100);
FORCEPROP 2 LAST CDS_LIB standard
J 0
(-2250 -1000);
DISPLAY INVISIBLE (-2250 -1000);
FORCEADD OFFPAGE..2
(2400 -325);
FORCEPROP 2 LAST $XR0 214 
J 0
(2589 -325);
DISPLAY 0.638298 (2589 -325);
PAINT MONO (2589 -325);
FORCEPROP 2 LAST CDS_LIB standard
J 0
(2400 -325);
DISPLAY INVISIBLE (2400 -325);
FORCEPROP 2 LAST PATH I178
J 0
(2575 -250);
DISPLAY 1.021277 (2575 -250);
DISPLAY INVISIBLE (2575 -250);
FORCEPROP 1 LAST COMMENT_BODY TRUE
J 0
(2355 -420);
DISPLAY 1.170213 (2355 -420);
PAINT GREEN (2355 -420);
DISPLAY INVISIBLE (2355 -420);
FORCEPROP 1 LAST OFFPAGE TRUE
J 0
(2725 -450);
DISPLAY 1.170213 (2725 -450);
PAINT GREEN (2725 -450);
DISPLAY INVISIBLE (2725 -450);
FORCEADD OFFPAGE..2
(250 -1425);
FORCEPROP 2 LAST $XR0 191 
J 0
(439 -1425);
DISPLAY 0.638298 (439 -1425);
PAINT MONO (439 -1425);
FORCEPROP 2 LAST PATH I179
J 0
(450 -1375);
DISPLAY 1.021277 (450 -1375);
DISPLAY INVISIBLE (450 -1375);
FORCEPROP 1 LAST COMMENT_BODY TRUE
J 0
(205 -1520);
DISPLAY 0.872340 (205 -1520);
PAINT PEACH (205 -1520);
DISPLAY INVISIBLE (205 -1520);
FORCEPROP 1 LAST OFFPAGE TRUE
J 0
(575 -1550);
DISPLAY 0.872340 (575 -1550);
PAINT GREEN (575 -1550);
DISPLAY INVISIBLE (575 -1550);
FORCEPROP 2 LAST CDS_LIB standard
J 0
(250 -1425);
PAINT MONO (250 -1425);
DISPLAY INVISIBLE (250 -1425);
FORCEADD OFFPAGE..1
R 2
(2400 925);
FORCEPROP 2 LAST $XR1 119 
J 0
(2676 925);
DISPLAY 0.638298 (2676 925);
PAINT MONO (2676 925);
FORCEPROP 2 LAST $XR0 44 
J 0
(2586 925);
DISPLAY 0.638298 (2586 925);
PAINT MONO (2586 925);
FORCEPROP 2 LAST PATH I18
J 0
(2700 975);
DISPLAY 1.021277 (2700 975);
DISPLAY INVISIBLE (2700 975);
FORCEPROP 2 LAST CDS_LIB standard
J 2
(2400 925);
DISPLAY INVISIBLE (2400 925);
FORCEPROP 1 LAST COMMENT_BODY TRUE
J 2
(2275 825);
DISPLAY 1.170213 (2275 825);
PAINT GREEN (2275 825);
DISPLAY INVISIBLE (2275 825);
FORCEPROP 1 LAST OFFPAGE TRUE
J 2
(2075 800);
DISPLAY 0.872340 (2075 800);
DISPLAY INVISIBLE (2075 800);
FORCEADD Q_RES..1
(-1025 -1425);
FORCEPROP 1 LAST PART_NUMBER CS00002JB13
J 0
(-1075 -1375);
DISPLAY 0.404255 (-1075 -1375);
DISPLAY INVISIBLE (-1075 -1375);
FORCEPROP 1 LAST TOLERANCE 5%
J 0
(-850 -1425);
DISPLAY 0.510638 (-850 -1425);
FORCEPROP 1 LAST MATERIAL CHIP
J 0
(-775 -1425);
DISPLAY 0.510638 (-775 -1425);
FORCEPROP 1 LAST $LOCATION R4606
J 0
(-1225 -1425);
DISPLAY 0.510638 (-1225 -1425);
FORCEPROP 1 LASTPIN (-1125 -1425) $PN 1
J 0
(-1113 -1413);
DISPLAY 0.787234 (-1113 -1413);
PAINT MONO (-1113 -1413);
FORCEPROP 1 LASTPIN (-925 -1425) $PN 2
J 0
(-963 -1413);
DISPLAY 0.787234 (-963 -1413);
PAINT MONO (-963 -1413);
FORCEPROP 1 LAST VALUE 0
J 2
(-875 -1425);
DISPLAY 0.510638 (-875 -1425);
FORCEPROP 1 LAST PATH I180
J 0
(-1075 -1275);
DISPLAY 0.978723 (-1075 -1275);
PAINT WHITE (-1075 -1275);
DISPLAY INVISIBLE (-1075 -1275);
FORCEPROP 2 LAST CDS_LIB pure_quanta
J 0
(-1025 -1425);
DISPLAY INVISIBLE (-1025 -1425);
FORCEPROP 1 LAST PACK_TYPE 0402LF
J 0
(-775 -1425);
DISPLAY 0.510638 (-775 -1425);
DISPLAY INVISIBLE (-775 -1425);
FORCEPROP 1 LAST WATTAGE 1/16W
J 2
(-850 -1350);
DISPLAY 0.404255 (-850 -1350);
DISPLAY INVISIBLE (-850 -1350);
FORCEPROP 0 LAST CDS_LOCATION R4606
J 0
(-1225 -1375);
DISPLAY 1.021277 (-1225 -1375);
DISPLAY INVISIBLE (-1225 -1375);
FORCEPROP 0 LAST $SEC 1
J 0
(-1225 -1375);
DISPLAY 0.680851 (-1225 -1375);
PAINT MONO (-1225 -1375);
DISPLAY INVISIBLE (-1225 -1375);
FORCEPROP 0 LAST CDS_SEC 1
J 0
(-1225 -1375);
DISPLAY 1.021277 (-1225 -1375);
DISPLAY INVISIBLE (-1225 -1375);
FORCEADD OFFPAGE..1
(-2250 -1425);
FORCEPROP 2 LAST $XR0 214 
J 0
(-2502 -1425);
DISPLAY 0.638298 (-2502 -1425);
PAINT MONO (-2502 -1425);
FORCEPROP 2 LAST PATH I181
J 0
(-2500 -1375);
DISPLAY 1.021277 (-2500 -1375);
DISPLAY INVISIBLE (-2500 -1375);
FORCEPROP 1 LAST OFFPAGE TRUE
J 0
(-1925 -1550);
DISPLAY 0.872340 (-1925 -1550);
DISPLAY INVISIBLE (-1925 -1550);
FORCEPROP 1 LAST COMMENT_BODY TRUE
J 0
(-2125 -1525);
DISPLAY 1.170213 (-2125 -1525);
PAINT GREEN (-2125 -1525);
DISPLAY INVISIBLE (-2125 -1525);
FORCEPROP 2 LAST CDS_LIB standard
J 0
(-2250 -1425);
DISPLAY INVISIBLE (-2250 -1425);
FORCEADD OFFPAGE..2
(250 -1625);
FORCEPROP 2 LAST $XR0 214 
J 0
(439 -1625);
DISPLAY 0.638298 (439 -1625);
PAINT MONO (439 -1625);
FORCEPROP 1 LAST COMMENT_BODY TRUE
J 0
(205 -1720);
DISPLAY 0.872340 (205 -1720);
PAINT PEACH (205 -1720);
DISPLAY INVISIBLE (205 -1720);
FORCEPROP 1 LAST OFFPAGE TRUE
J 0
(575 -1750);
DISPLAY 0.872340 (575 -1750);
PAINT GREEN (575 -1750);
DISPLAY INVISIBLE (575 -1750);
FORCEPROP 2 LAST CDS_LIB standard
J 0
(250 -1625);
PAINT MONO (250 -1625);
DISPLAY INVISIBLE (250 -1625);
FORCEPROP 2 LAST PATH I182
J 0
(450 -1575);
DISPLAY 1.021277 (450 -1575);
DISPLAY INVISIBLE (450 -1575);
FORCEADD Q_RES..1
(-1025 -1625);
FORCEPROP 1 LAST PART_NUMBER CS00002JB13
J 0
(-1075 -1575);
DISPLAY 0.404255 (-1075 -1575);
DISPLAY INVISIBLE (-1075 -1575);
FORCEPROP 1 LAST MATERIAL CHIP
J 0
(-775 -1625);
DISPLAY 0.510638 (-775 -1625);
FORCEPROP 1 LAST TOLERANCE 5%
J 0
(-850 -1625);
DISPLAY 0.510638 (-850 -1625);
FORCEPROP 1 LAST VALUE 0
J 2
(-875 -1625);
DISPLAY 0.510638 (-875 -1625);
FORCEPROP 1 LAST $LOCATION R4607
J 0
(-1225 -1625);
DISPLAY 0.510638 (-1225 -1625);
FORCEPROP 1 LASTPIN (-1125 -1625) $PN 1
J 0
(-1113 -1613);
DISPLAY 0.787234 (-1113 -1613);
PAINT MONO (-1113 -1613);
FORCEPROP 1 LASTPIN (-925 -1625) $PN 2
J 0
(-963 -1613);
DISPLAY 0.787234 (-963 -1613);
PAINT MONO (-963 -1613);
FORCEPROP 2 LAST CDS_LIB pure_quanta
J 0
(-1025 -1625);
DISPLAY INVISIBLE (-1025 -1625);
FORCEPROP 1 LAST PACK_TYPE 0402LF
J 0
(-775 -1625);
DISPLAY 0.510638 (-775 -1625);
DISPLAY INVISIBLE (-775 -1625);
FORCEPROP 1 LAST WATTAGE 1/16W
J 2
(-850 -1550);
DISPLAY 0.404255 (-850 -1550);
DISPLAY INVISIBLE (-850 -1550);
FORCEPROP 1 LAST PATH I183
J 0
(-1075 -1475);
DISPLAY 0.978723 (-1075 -1475);
PAINT WHITE (-1075 -1475);
DISPLAY INVISIBLE (-1075 -1475);
FORCEPROP 0 LAST CDS_LOCATION R4607
J 0
(-1225 -1575);
DISPLAY 1.021277 (-1225 -1575);
DISPLAY INVISIBLE (-1225 -1575);
FORCEPROP 0 LAST $SEC 1
J 0
(-1225 -1575);
DISPLAY 0.680851 (-1225 -1575);
PAINT MONO (-1225 -1575);
DISPLAY INVISIBLE (-1225 -1575);
FORCEPROP 0 LAST CDS_SEC 1
J 0
(-1225 -1575);
DISPLAY 1.021277 (-1225 -1575);
DISPLAY INVISIBLE (-1225 -1575);
FORCEADD OFFPAGE..1
(-2250 -1625);
FORCEPROP 2 LAST $XR1 240 
J 0
(-2622 -1625);
DISPLAY 0.638298 (-2622 -1625);
PAINT MONO (-2622 -1625);
FORCEPROP 2 LAST $XR0 190 
J 0
(-2502 -1625);
DISPLAY 0.638298 (-2502 -1625);
PAINT MONO (-2502 -1625);
FORCEPROP 2 LAST CDS_LIB standard
J 0
(-2250 -1625);
DISPLAY INVISIBLE (-2250 -1625);
FORCEPROP 2 LAST PATH I184
J 0
(-2500 -1575);
DISPLAY 1.021277 (-2500 -1575);
DISPLAY INVISIBLE (-2500 -1575);
FORCEPROP 1 LAST OFFPAGE TRUE
J 0
(-1925 -1750);
DISPLAY 0.872340 (-1925 -1750);
DISPLAY INVISIBLE (-1925 -1750);
FORCEPROP 1 LAST COMMENT_BODY TRUE
J 0
(-2125 -1725);
DISPLAY 1.170213 (-2125 -1725);
PAINT GREEN (-2125 -1725);
DISPLAY INVISIBLE (-2125 -1725);
FORCEADD OFFPAGE..2
(2400 -375);
FORCEPROP 2 LAST $XR0 214 
J 0
(2589 -375);
DISPLAY 0.638298 (2589 -375);
PAINT MONO (2589 -375);
FORCEPROP 2 LAST CDS_LIB standard
J 0
(2400 -375);
DISPLAY INVISIBLE (2400 -375);
FORCEPROP 2 LAST PATH I185
J 0
(2575 -300);
DISPLAY 1.021277 (2575 -300);
DISPLAY INVISIBLE (2575 -300);
FORCEPROP 1 LAST OFFPAGE TRUE
J 0
(2725 -500);
DISPLAY 1.170213 (2725 -500);
PAINT GREEN (2725 -500);
DISPLAY INVISIBLE (2725 -500);
FORCEPROP 1 LAST COMMENT_BODY TRUE
J 0
(2355 -470);
DISPLAY 1.170213 (2355 -470);
PAINT GREEN (2355 -470);
DISPLAY INVISIBLE (2355 -470);
FORCEADD OFFPAGE..5
R 2
(250 -1900);
FORCEPROP 2 LAST $XR0 151 
J 0
(439 -1900);
DISPLAY 0.638298 (439 -1900);
PAINT MONO (439 -1900);
FORCEPROP 2 LAST PATH I186
J 2
(500 -1850);
DISPLAY 1.021277 (500 -1850);
DISPLAY INVISIBLE (500 -1850);
FORCEPROP 2 LAST CDS_LIB standard
J 2
(250 -1900);
DISPLAY INVISIBLE (250 -1900);
FORCEPROP 1 LAST OFFPAGE TRUE
J 2
(-75 -2025);
DISPLAY 0.872340 (-75 -2025);
PAINT GREEN (-75 -2025);
DISPLAY INVISIBLE (-75 -2025);
FORCEPROP 1 LAST COMMENT_BODY TRUE
J 2
(150 -1975);
DISPLAY 0.872340 (150 -1975);
PAINT PEACH (150 -1975);
DISPLAY INVISIBLE (150 -1975);
FORCEADD OFFPAGE..1
(-2250 -1900);
FORCEPROP 2 LAST $XR0 214 
J 0
(-2502 -1900);
DISPLAY 0.638298 (-2502 -1900);
PAINT MONO (-2502 -1900);
FORCEPROP 2 LAST PATH I188
J 2
(-2425 -1825);
DISPLAY 1.021277 (-2425 -1825);
DISPLAY INVISIBLE (-2425 -1825);
FORCEPROP 1 LAST OFFPAGE TRUE
J 0
(-1925 -2025);
DISPLAY 0.872340 (-1925 -2025);
DISPLAY INVISIBLE (-1925 -2025);
FORCEPROP 1 LAST COMMENT_BODY TRUE
J 0
(-2125 -2000);
DISPLAY 1.170213 (-2125 -2000);
PAINT GREEN (-2125 -2000);
DISPLAY INVISIBLE (-2125 -2000);
FORCEPROP 2 LAST CDS_LIB standard
J 0
(-2250 -1900);
DISPLAY INVISIBLE (-2250 -1900);
FORCEADD OFFPAGE..2
(2400 -425);
FORCEPROP 2 LAST $XR0 214 
J 0
(2589 -425);
DISPLAY 0.638298 (2589 -425);
PAINT MONO (2589 -425);
FORCEPROP 2 LAST CDS_LIB standard
J 0
(2400 -425);
DISPLAY INVISIBLE (2400 -425);
FORCEPROP 2 LAST PATH I189
J 0
(2575 -350);
DISPLAY 1.021277 (2575 -350);
DISPLAY INVISIBLE (2575 -350);
FORCEPROP 1 LAST COMMENT_BODY TRUE
J 0
(2355 -520);
DISPLAY 1.170213 (2355 -520);
PAINT GREEN (2355 -520);
DISPLAY INVISIBLE (2355 -520);
FORCEPROP 1 LAST OFFPAGE TRUE
J 0
(2725 -550);
DISPLAY 1.170213 (2725 -550);
PAINT GREEN (2725 -550);
DISPLAY INVISIBLE (2725 -550);
FORCEADD OFFPAGE..1
R 2
(2400 875);
FORCEPROP 2 LAST $XR0 214 
J 0
(2586 875);
DISPLAY 0.638298 (2586 875);
PAINT MONO (2586 875);
FORCEPROP 2 LAST PATH I19
J 0
(2600 925);
DISPLAY 1.021277 (2600 925);
DISPLAY INVISIBLE (2600 925);
FORCEPROP 1 LAST COMMENT_BODY TRUE
J 2
(2275 775);
DISPLAY 1.170213 (2275 775);
PAINT GREEN (2275 775);
DISPLAY INVISIBLE (2275 775);
FORCEPROP 1 LAST OFFPAGE TRUE
J 2
(2075 750);
DISPLAY 0.872340 (2075 750);
DISPLAY INVISIBLE (2075 750);
FORCEPROP 2 LAST CDS_LIB standard
J 2
(2400 875);
DISPLAY INVISIBLE (2400 875);
FORCEADD Q_RES..1
(-1050 -1900);
FORCEPROP 1 LAST PART_NUMBER CS03322FB03
J 0
(-1200 -1850);
DISPLAY 0.638298 (-1200 -1850);
DISPLAY INVISIBLE (-1200 -1850);
FORCEPROP 1 LAST VALUE 33.2
J 2
(-800 -1900);
DISPLAY 0.638298 (-800 -1900);
FORCEPROP 1 LAST WATTAGE 1/16W
J 2
(-850 -1800);
DISPLAY 0.638298 (-850 -1800);
FORCEPROP 1 LAST TOLERANCE 1%
J 0
(-775 -1900);
DISPLAY 0.638298 (-775 -1900);
FORCEPROP 1 LAST MATERIAL CHIP
J 0
(-700 -1900);
DISPLAY 0.638298 (-700 -1900);
FORCEPROP 1 LAST PACK_TYPE 0402LF
J 0
(-1200 -1800);
DISPLAY 0.638298 (-1200 -1800);
FORCEPROP 1 LAST $LOCATION R4608
J 0
(-1275 -1900);
DISPLAY 0.787234 (-1275 -1900);
FORCEPROP 1 LASTPIN (-1150 -1900) $PN 1
J 0
(-1138 -1888);
DISPLAY 0.787234 (-1138 -1888);
PAINT MONO (-1138 -1888);
FORCEPROP 1 LASTPIN (-950 -1900) $PN 2
J 0
(-988 -1888);
DISPLAY 0.787234 (-988 -1888);
PAINT MONO (-988 -1888);
FORCEPROP 1 LAST PATH I190
J 0
(-1100 -1750);
DISPLAY 0.978723 (-1100 -1750);
PAINT WHITE (-1100 -1750);
DISPLAY INVISIBLE (-1100 -1750);
FORCEPROP 2 LAST CDS_LIB pure_quanta
J 0
(-1050 -1900);
DISPLAY INVISIBLE (-1050 -1900);
FORCEPROP 0 LAST CDS_LOCATION R4608
J 0
(-850 -1750);
DISPLAY 1.021277 (-850 -1750);
DISPLAY INVISIBLE (-850 -1750);
FORCEPROP 0 LAST $SEC 1
J 0
(-850 -1750);
DISPLAY 0.680851 (-850 -1750);
PAINT MONO (-850 -1750);
DISPLAY INVISIBLE (-850 -1750);
FORCEPROP 0 LAST CDS_SEC 1
J 0
(-850 -1750);
DISPLAY 1.021277 (-850 -1750);
DISPLAY INVISIBLE (-850 -1750);
FORCEADD OFFPAGE..5
R 2
(250 -2125);
FORCEPROP 2 LAST $XR0 134 
J 0
(439 -2125);
DISPLAY 0.638298 (439 -2125);
PAINT MONO (439 -2125);
FORCEPROP 2 LAST PATH I193
J 0
(525 -2075);
DISPLAY 1.021277 (525 -2075);
DISPLAY INVISIBLE (525 -2075);
FORCEPROP 2 LAST CDS_LIB standard
J 2
(250 -2125);
DISPLAY INVISIBLE (250 -2125);
FORCEPROP 1 LAST OFFPAGE TRUE
J 2
(-75 -2250);
DISPLAY 0.872340 (-75 -2250);
PAINT GREEN (-75 -2250);
DISPLAY INVISIBLE (-75 -2250);
FORCEPROP 1 LAST COMMENT_BODY TRUE
J 2
(150 -2200);
DISPLAY 0.872340 (150 -2200);
PAINT PEACH (150 -2200);
DISPLAY INVISIBLE (150 -2200);
FORCEADD Q_RES..1
(-1050 -2125);
FORCEPROP 1 LAST PART_NUMBER CS03322FB03
J 0
(-1200 -2050);
DISPLAY 0.638298 (-1200 -2050);
DISPLAY INVISIBLE (-1200 -2050);
FORCEPROP 1 LAST MATERIAL CHIP
J 0
(-750 -2125);
DISPLAY 0.638298 (-750 -2125);
FORCEPROP 1 LAST VALUE 33.2
J 2
(-800 -2125);
DISPLAY 0.638298 (-800 -2125);
FORCEPROP 1 LAST $LOCATION R4609
J 0
(-1275 -2125);
DISPLAY 0.787234 (-1275 -2125);
FORCEPROP 1 LASTPIN (-1150 -2125) $PN 1
J 0
(-1138 -2113);
DISPLAY 0.787234 (-1138 -2113);
PAINT MONO (-1138 -2113);
FORCEPROP 1 LASTPIN (-950 -2125) $PN 2
J 0
(-988 -2113);
DISPLAY 0.787234 (-988 -2113);
PAINT MONO (-988 -2113);
FORCEPROP 1 LAST PATH I194
J 0
(-1100 -1975);
DISPLAY 0.978723 (-1100 -1975);
PAINT WHITE (-1100 -1975);
DISPLAY INVISIBLE (-1100 -1975);
FORCEPROP 1 LAST WATTAGE 1/16W
J 2
(-850 -2000);
DISPLAY 0.638298 (-850 -2000);
DISPLAY INVISIBLE (-850 -2000);
FORCEPROP 1 LAST PACK_TYPE 0402LF
J 0
(-1200 -2000);
DISPLAY 0.638298 (-1200 -2000);
DISPLAY INVISIBLE (-1200 -2000);
FORCEPROP 1 LAST TOLERANCE 1%
J 0
(-775 -2125);
DISPLAY 0.638298 (-775 -2125);
DISPLAY INVISIBLE (-775 -2125);
FORCEPROP 2 LAST CDS_LIB pure_quanta
J 0
(-1050 -2125);
DISPLAY INVISIBLE (-1050 -2125);
FORCEPROP 0 LAST CDS_LOCATION R4609
J 0
(-750 -2075);
DISPLAY 1.021277 (-750 -2075);
DISPLAY INVISIBLE (-750 -2075);
FORCEPROP 0 LAST $SEC 1
J 0
(-750 -2075);
DISPLAY 0.680851 (-750 -2075);
PAINT MONO (-750 -2075);
DISPLAY INVISIBLE (-750 -2075);
FORCEPROP 0 LAST CDS_SEC 1
J 0
(-750 -2075);
DISPLAY 1.021277 (-750 -2075);
DISPLAY INVISIBLE (-750 -2075);
FORCEADD OFFPAGE..1
(-2250 -2125);
FORCEPROP 2 LAST $XR0 214 
J 0
(-2502 -2125);
DISPLAY 0.638298 (-2502 -2125);
PAINT MONO (-2502 -2125);
FORCEPROP 2 LAST PATH I195
J 0
(-2200 -2050);
DISPLAY 1.021277 (-2200 -2050);
DISPLAY INVISIBLE (-2200 -2050);
FORCEPROP 1 LAST OFFPAGE TRUE
J 0
(-1925 -2250);
DISPLAY 0.872340 (-1925 -2250);
DISPLAY INVISIBLE (-1925 -2250);
FORCEPROP 1 LAST COMMENT_BODY TRUE
J 0
(-2125 -2225);
DISPLAY 1.170213 (-2125 -2225);
PAINT GREEN (-2125 -2225);
DISPLAY INVISIBLE (-2125 -2225);
FORCEPROP 2 LAST CDS_LIB standard
J 0
(-2250 -2125);
DISPLAY INVISIBLE (-2250 -2125);
FORCEADD OFFPAGE..2
(2400 -475);
FORCEPROP 2 LAST $XR0 214 
J 0
(2589 -475);
DISPLAY 0.638298 (2589 -475);
PAINT MONO (2589 -475);
FORCEPROP 2 LAST CDS_LIB standard
J 0
(2400 -475);
DISPLAY INVISIBLE (2400 -475);
FORCEPROP 2 LAST PATH I196
J 0
(2575 -400);
DISPLAY 1.021277 (2575 -400);
DISPLAY INVISIBLE (2575 -400);
FORCEPROP 1 LAST OFFPAGE TRUE
J 0
(2725 -600);
DISPLAY 1.170213 (2725 -600);
PAINT GREEN (2725 -600);
DISPLAY INVISIBLE (2725 -600);
FORCEPROP 1 LAST COMMENT_BODY TRUE
J 0
(2355 -570);
DISPLAY 1.170213 (2355 -570);
PAINT GREEN (2355 -570);
DISPLAY INVISIBLE (2355 -570);
FORCEADD OFFPAGE..5
R 2
(250 -2350);
FORCEPROP 2 LAST $XR0 212 
J 0
(439 -2350);
DISPLAY 0.638298 (439 -2350);
PAINT MONO (439 -2350);
FORCEPROP 2 LAST PATH I199
J 0
(525 -2300);
DISPLAY 1.021277 (525 -2300);
DISPLAY INVISIBLE (525 -2300);
FORCEPROP 2 LAST CDS_LIB standard
J 2
(250 -2350);
DISPLAY INVISIBLE (250 -2350);
FORCEPROP 1 LAST OFFPAGE TRUE
J 2
(-75 -2475);
DISPLAY 0.872340 (-75 -2475);
PAINT GREEN (-75 -2475);
DISPLAY INVISIBLE (-75 -2475);
FORCEPROP 1 LAST COMMENT_BODY TRUE
J 2
(150 -2425);
DISPLAY 0.872340 (150 -2425);
PAINT PEACH (150 -2425);
DISPLAY INVISIBLE (150 -2425);
FORCEADD OFFPAGE..1
R 2
(2400 825);
FORCEPROP 2 LAST $XR0 266 
J 0
(2586 825);
DISPLAY 0.638298 (2586 825);
PAINT MONO (2586 825);
FORCEPROP 2 LAST PATH I20
J 0
(2725 875);
DISPLAY 1.021277 (2725 875);
DISPLAY INVISIBLE (2725 875);
FORCEPROP 2 LAST CDS_LIB standard
J 0
(2400 825);
DISPLAY INVISIBLE (2400 825);
FORCEPROP 1 LAST COMMENT_BODY TRUE
J 2
(2275 725);
DISPLAY 1.170213 (2275 725);
PAINT GREEN (2275 725);
DISPLAY INVISIBLE (2275 725);
FORCEPROP 1 LAST OFFPAGE TRUE
J 2
(2075 700);
DISPLAY 1.170213 (2075 700);
PAINT GREEN (2075 700);
DISPLAY INVISIBLE (2075 700);
FORCEADD Q_RES..1
(-1050 -2350);
FORCEPROP 1 LAST PART_NUMBER CS03322FB03
J 0
(-1200 -2275);
DISPLAY 0.638298 (-1200 -2275);
DISPLAY INVISIBLE (-1200 -2275);
FORCEPROP 1 LAST VALUE 33.2
J 2
(-800 -2350);
DISPLAY 0.638298 (-800 -2350);
FORCEPROP 1 LAST MATERIAL CHIP
J 0
(-750 -2350);
DISPLAY 0.638298 (-750 -2350);
FORCEPROP 1 LAST $LOCATION R4610
J 0
(-1275 -2350);
DISPLAY 0.787234 (-1275 -2350);
FORCEPROP 1 LASTPIN (-1150 -2350) $PN 1
J 0
(-1138 -2338);
DISPLAY 0.787234 (-1138 -2338);
PAINT MONO (-1138 -2338);
FORCEPROP 1 LASTPIN (-950 -2350) $PN 2
J 0
(-988 -2338);
DISPLAY 0.787234 (-988 -2338);
PAINT MONO (-988 -2338);
FORCEPROP 1 LAST PATH I200
J 0
(-1100 -2200);
DISPLAY 0.978723 (-1100 -2200);
PAINT WHITE (-1100 -2200);
DISPLAY INVISIBLE (-1100 -2200);
FORCEPROP 1 LAST WATTAGE 1/16W
J 2
(-850 -2225);
DISPLAY 0.638298 (-850 -2225);
DISPLAY INVISIBLE (-850 -2225);
FORCEPROP 1 LAST PACK_TYPE 0402LF
J 0
(-1200 -2225);
DISPLAY 0.638298 (-1200 -2225);
DISPLAY INVISIBLE (-1200 -2225);
FORCEPROP 1 LAST TOLERANCE 1%
J 0
(-775 -2350);
DISPLAY 0.638298 (-775 -2350);
DISPLAY INVISIBLE (-775 -2350);
FORCEPROP 2 LAST CDS_LIB pure_quanta
J 0
(-1050 -2350);
DISPLAY INVISIBLE (-1050 -2350);
FORCEPROP 0 LAST CDS_LOCATION R4610
J 0
(-750 -2300);
DISPLAY 1.021277 (-750 -2300);
DISPLAY INVISIBLE (-750 -2300);
FORCEPROP 0 LAST $SEC 1
J 0
(-750 -2300);
DISPLAY 0.680851 (-750 -2300);
PAINT MONO (-750 -2300);
DISPLAY INVISIBLE (-750 -2300);
FORCEPROP 0 LAST CDS_SEC 1
J 0
(-750 -2300);
DISPLAY 1.021277 (-750 -2300);
DISPLAY INVISIBLE (-750 -2300);
FORCEADD OFFPAGE..1
(-2250 -2350);
FORCEPROP 2 LAST $XR0 214 
J 0
(-2502 -2350);
DISPLAY 0.638298 (-2502 -2350);
PAINT MONO (-2502 -2350);
FORCEPROP 2 LAST PATH I201
J 0
(-2200 -2275);
DISPLAY 1.021277 (-2200 -2275);
DISPLAY INVISIBLE (-2200 -2275);
FORCEPROP 1 LAST OFFPAGE TRUE
J 0
(-1925 -2475);
DISPLAY 0.872340 (-1925 -2475);
DISPLAY INVISIBLE (-1925 -2475);
FORCEPROP 1 LAST COMMENT_BODY TRUE
J 0
(-2125 -2450);
DISPLAY 1.170213 (-2125 -2450);
PAINT GREEN (-2125 -2450);
DISPLAY INVISIBLE (-2125 -2450);
FORCEPROP 2 LAST CDS_LIB standard
J 0
(-2250 -2350);
DISPLAY INVISIBLE (-2250 -2350);
FORCEADD OFFPAGE..2
(2400 -525);
FORCEPROP 2 LAST $XR0 214 
J 0
(2589 -525);
DISPLAY 0.638298 (2589 -525);
PAINT MONO (2589 -525);
FORCEPROP 2 LAST CDS_LIB standard
J 0
(2400 -525);
DISPLAY INVISIBLE (2400 -525);
FORCEPROP 2 LAST PATH I202
J 0
(2575 -450);
DISPLAY 1.021277 (2575 -450);
DISPLAY INVISIBLE (2575 -450);
FORCEPROP 1 LAST COMMENT_BODY TRUE
J 0
(2355 -620);
DISPLAY 1.170213 (2355 -620);
PAINT GREEN (2355 -620);
DISPLAY INVISIBLE (2355 -620);
FORCEPROP 1 LAST OFFPAGE TRUE
J 0
(2725 -650);
DISPLAY 1.170213 (2725 -650);
PAINT GREEN (2725 -650);
DISPLAY INVISIBLE (2725 -650);
FORCEADD OFFPAGE..5
R 2
(250 -2525);
FORCEPROP 2 LAST $XR0 239 
J 0
(439 -2525);
DISPLAY 0.638298 (439 -2525);
PAINT MONO (439 -2525);
FORCEPROP 2 LAST PATH I205
J 0
(525 -2475);
DISPLAY 1.021277 (525 -2475);
DISPLAY INVISIBLE (525 -2475);
FORCEPROP 1 LAST COMMENT_BODY TRUE
J 2
(150 -2600);
DISPLAY 0.872340 (150 -2600);
PAINT PEACH (150 -2600);
DISPLAY INVISIBLE (150 -2600);
FORCEPROP 1 LAST OFFPAGE TRUE
J 2
(-75 -2650);
DISPLAY 0.872340 (-75 -2650);
PAINT GREEN (-75 -2650);
DISPLAY INVISIBLE (-75 -2650);
FORCEPROP 2 LAST CDS_LIB standard
J 2
(250 -2525);
DISPLAY INVISIBLE (250 -2525);
FORCEADD Q_RES..1
(-1050 -2525);
FORCEPROP 1 LAST PART_NUMBER CS03322FB03
J 0
(-1200 -2450);
DISPLAY 0.638298 (-1200 -2450);
DISPLAY INVISIBLE (-1200 -2450);
FORCEPROP 1 LAST VALUE 33.2
J 2
(-800 -2525);
DISPLAY 0.638298 (-800 -2525);
FORCEPROP 1 LAST MATERIAL CHIP
J 0
(-750 -2525);
DISPLAY 0.638298 (-750 -2525);
FORCEPROP 1 LAST $LOCATION R4611
J 0
(-1275 -2525);
DISPLAY 0.787234 (-1275 -2525);
FORCEPROP 1 LASTPIN (-1150 -2525) $PN 1
J 0
(-1138 -2513);
DISPLAY 0.787234 (-1138 -2513);
PAINT MONO (-1138 -2513);
FORCEPROP 1 LASTPIN (-950 -2525) $PN 2
J 0
(-988 -2513);
DISPLAY 0.787234 (-988 -2513);
PAINT MONO (-988 -2513);
FORCEPROP 1 LAST PATH I206
J 0
(-1100 -2375);
DISPLAY 0.978723 (-1100 -2375);
PAINT WHITE (-1100 -2375);
DISPLAY INVISIBLE (-1100 -2375);
FORCEPROP 2 LAST CDS_LIB pure_quanta
J 0
(-1050 -2525);
DISPLAY INVISIBLE (-1050 -2525);
FORCEPROP 1 LAST TOLERANCE 1%
J 0
(-775 -2525);
DISPLAY 0.638298 (-775 -2525);
DISPLAY INVISIBLE (-775 -2525);
FORCEPROP 1 LAST PACK_TYPE 0402LF
J 0
(-1200 -2400);
DISPLAY 0.638298 (-1200 -2400);
DISPLAY INVISIBLE (-1200 -2400);
FORCEPROP 1 LAST WATTAGE 1/16W
J 2
(-850 -2400);
DISPLAY 0.638298 (-850 -2400);
DISPLAY INVISIBLE (-850 -2400);
FORCEPROP 0 LAST CDS_LOCATION R4611
J 0
(-750 -2475);
DISPLAY 1.021277 (-750 -2475);
DISPLAY INVISIBLE (-750 -2475);
FORCEPROP 0 LAST $SEC 1
J 0
(-750 -2475);
DISPLAY 0.680851 (-750 -2475);
PAINT MONO (-750 -2475);
DISPLAY INVISIBLE (-750 -2475);
FORCEPROP 0 LAST CDS_SEC 1
J 0
(-750 -2475);
DISPLAY 1.021277 (-750 -2475);
DISPLAY INVISIBLE (-750 -2475);
FORCEADD OFFPAGE..1
(-2250 -2525);
FORCEPROP 2 LAST $XR0 214 
J 0
(-2502 -2525);
DISPLAY 0.638298 (-2502 -2525);
PAINT MONO (-2502 -2525);
FORCEPROP 2 LAST PATH I207
J 0
(-2200 -2450);
DISPLAY 1.021277 (-2200 -2450);
DISPLAY INVISIBLE (-2200 -2450);
FORCEPROP 2 LAST CDS_LIB standard
J 0
(-2250 -2525);
DISPLAY INVISIBLE (-2250 -2525);
FORCEPROP 1 LAST COMMENT_BODY TRUE
J 0
(-2125 -2625);
DISPLAY 1.170213 (-2125 -2625);
PAINT GREEN (-2125 -2625);
DISPLAY INVISIBLE (-2125 -2625);
FORCEPROP 1 LAST OFFPAGE TRUE
J 0
(-1925 -2650);
DISPLAY 0.872340 (-1925 -2650);
DISPLAY INVISIBLE (-1925 -2650);
FORCEADD OFFPAGE..2
(2400 -575);
FORCEPROP 2 LAST $XR0 214 
J 0
(2589 -575);
DISPLAY 0.638298 (2589 -575);
PAINT MONO (2589 -575);
FORCEPROP 2 LAST CDS_LIB standard
J 0
(2400 -575);
DISPLAY INVISIBLE (2400 -575);
FORCEPROP 2 LAST PATH I208
J 0
(2575 -500);
DISPLAY 1.021277 (2575 -500);
DISPLAY INVISIBLE (2575 -500);
FORCEPROP 1 LAST OFFPAGE TRUE
J 0
(2725 -700);
DISPLAY 1.170213 (2725 -700);
PAINT GREEN (2725 -700);
DISPLAY INVISIBLE (2725 -700);
FORCEPROP 1 LAST COMMENT_BODY TRUE
J 0
(2355 -670);
DISPLAY 1.170213 (2355 -670);
PAINT GREEN (2355 -670);
DISPLAY INVISIBLE (2355 -670);
FORCEADD OFFPAGE..1
R 2
(2400 775);
FORCEPROP 2 LAST $XR0 284 
J 0
(2586 775);
DISPLAY 0.638298 (2586 775);
PAINT MONO (2586 775);
FORCEPROP 2 LAST PATH I21
J 0
(2725 825);
DISPLAY 1.021277 (2725 825);
DISPLAY INVISIBLE (2725 825);
FORCEPROP 2 LAST CDS_LIB standard
J 0
(2400 775);
DISPLAY INVISIBLE (2400 775);
FORCEPROP 1 LAST COMMENT_BODY TRUE
J 2
(2275 675);
DISPLAY 1.170213 (2275 675);
PAINT GREEN (2275 675);
DISPLAY INVISIBLE (2275 675);
FORCEPROP 1 LAST OFFPAGE TRUE
J 2
(2075 650);
DISPLAY 1.170213 (2075 650);
PAINT GREEN (2075 650);
DISPLAY INVISIBLE (2075 650);
FORCEADD OFFPAGE..5
R 2
(250 -2675);
FORCEPROP 2 LAST $XR0 214 
J 0
(439 -2675);
DISPLAY 0.638298 (439 -2675);
PAINT MONO (439 -2675);
FORCEPROP 2 LAST CDS_LIB standard
J 2
(250 -2675);
DISPLAY INVISIBLE (250 -2675);
FORCEPROP 1 LAST OFFPAGE TRUE
J 2
(-75 -2800);
DISPLAY 0.872340 (-75 -2800);
PAINT GREEN (-75 -2800);
DISPLAY INVISIBLE (-75 -2800);
FORCEPROP 1 LAST COMMENT_BODY TRUE
J 2
(150 -2750);
DISPLAY 0.872340 (150 -2750);
PAINT PEACH (150 -2750);
DISPLAY INVISIBLE (150 -2750);
FORCEPROP 2 LAST PATH I210
J 0
(525 -2625);
DISPLAY 1.021277 (525 -2625);
DISPLAY INVISIBLE (525 -2625);
FORCEADD Q_RES..1
(-1050 -2675);
FORCEPROP 1 LAST PART_NUMBER CS03322FB03
J 0
(-1200 -2600);
DISPLAY 0.638298 (-1200 -2600);
DISPLAY INVISIBLE (-1200 -2600);
FORCEPROP 1 LAST VALUE 33.2
J 2
(-800 -2675);
DISPLAY 0.638298 (-800 -2675);
FORCEPROP 1 LAST MATERIAL CHIP
J 0
(-750 -2675);
DISPLAY 0.638298 (-750 -2675);
FORCEPROP 1 LAST $LOCATION R4612
J 0
(-1275 -2675);
DISPLAY 0.787234 (-1275 -2675);
FORCEPROP 1 LASTPIN (-1150 -2675) $PN 1
J 0
(-1138 -2663);
DISPLAY 0.787234 (-1138 -2663);
PAINT MONO (-1138 -2663);
FORCEPROP 1 LASTPIN (-950 -2675) $PN 2
J 0
(-988 -2663);
DISPLAY 0.787234 (-988 -2663);
PAINT MONO (-988 -2663);
FORCEPROP 1 LAST WATTAGE 1/16W
J 2
(-850 -2550);
DISPLAY 0.638298 (-850 -2550);
DISPLAY INVISIBLE (-850 -2550);
FORCEPROP 1 LAST PACK_TYPE 0402LF
J 0
(-1200 -2550);
DISPLAY 0.638298 (-1200 -2550);
DISPLAY INVISIBLE (-1200 -2550);
FORCEPROP 1 LAST TOLERANCE 1%
J 0
(-775 -2675);
DISPLAY 0.638298 (-775 -2675);
DISPLAY INVISIBLE (-775 -2675);
FORCEPROP 2 LAST CDS_LIB pure_quanta
J 0
(-1050 -2675);
DISPLAY INVISIBLE (-1050 -2675);
FORCEPROP 1 LAST PATH I211
J 0
(-1100 -2525);
DISPLAY 0.978723 (-1100 -2525);
PAINT WHITE (-1100 -2525);
DISPLAY INVISIBLE (-1100 -2525);
FORCEPROP 0 LAST CDS_LOCATION R4612
J 0
(-750 -2625);
DISPLAY 1.021277 (-750 -2625);
DISPLAY INVISIBLE (-750 -2625);
FORCEPROP 0 LAST $SEC 1
J 0
(-750 -2625);
DISPLAY 0.680851 (-750 -2625);
PAINT MONO (-750 -2625);
DISPLAY INVISIBLE (-750 -2625);
FORCEPROP 0 LAST CDS_SEC 1
J 0
(-750 -2625);
DISPLAY 1.021277 (-750 -2625);
DISPLAY INVISIBLE (-750 -2625);
FORCEADD OFFPAGE..1
(-2250 -2675);
FORCEPROP 2 LAST $XR2 240 
J 0
(-2742 -2675);
DISPLAY 0.638298 (-2742 -2675);
PAINT MONO (-2742 -2675);
FORCEPROP 2 LAST $XR1 198 
J 0
(-2622 -2675);
DISPLAY 0.638298 (-2622 -2675);
PAINT MONO (-2622 -2675);
FORCEPROP 2 LAST $XR0 185 
J 0
(-2502 -2675);
DISPLAY 0.638298 (-2502 -2675);
PAINT MONO (-2502 -2675);
FORCEPROP 1 LAST OFFPAGE TRUE
J 0
(-1925 -2800);
DISPLAY 0.872340 (-1925 -2800);
DISPLAY INVISIBLE (-1925 -2800);
FORCEPROP 1 LAST COMMENT_BODY TRUE
J 0
(-2125 -2775);
DISPLAY 1.170213 (-2125 -2775);
PAINT GREEN (-2125 -2775);
DISPLAY INVISIBLE (-2125 -2775);
FORCEPROP 2 LAST CDS_LIB standard
J 0
(-2250 -2675);
DISPLAY INVISIBLE (-2250 -2675);
FORCEPROP 2 LAST PATH I212
J 0
(-2200 -2600);
DISPLAY 1.021277 (-2200 -2600);
DISPLAY INVISIBLE (-2200 -2600);
FORCEADD OFFPAGE..1
R 2
(2400 -625);
FORCEPROP 2 LAST $XR0 214 
J 0
(2586 -625);
DISPLAY 0.638298 (2586 -625);
PAINT MONO (2586 -625);
FORCEPROP 1 LAST OFFPAGE TRUE
J 2
(2075 -750);
DISPLAY 0.872340 (2075 -750);
PAINT GREEN (2075 -750);
DISPLAY INVISIBLE (2075 -750);
FORCEPROP 1 LAST COMMENT_BODY TRUE
J 2
(2275 -725);
DISPLAY 0.872340 (2275 -725);
PAINT GREEN (2275 -725);
DISPLAY INVISIBLE (2275 -725);
FORCEPROP 2 LAST PATH I213
J 0
(2575 -550);
DISPLAY 1.021277 (2575 -550);
DISPLAY INVISIBLE (2575 -550);
FORCEPROP 2 LAST CDS_LIB standard
J 0
(2400 -625);
DISPLAY INVISIBLE (2400 -625);
FORCEADD OFFPAGE..2
(2400 -675);
FORCEPROP 2 LAST $XR1 223 
J 0
(2709 -675);
DISPLAY 0.638298 (2709 -675);
PAINT MONO (2709 -675);
FORCEPROP 2 LAST $XR0 219 
J 0
(2589 -675);
DISPLAY 0.638298 (2589 -675);
PAINT MONO (2589 -675);
FORCEPROP 1 LAST COMMENT_BODY TRUE
J 0
(2355 -770);
DISPLAY 1.170213 (2355 -770);
PAINT GREEN (2355 -770);
DISPLAY INVISIBLE (2355 -770);
FORCEPROP 1 LAST OFFPAGE TRUE
J 0
(2725 -800);
DISPLAY 1.170213 (2725 -800);
PAINT GREEN (2725 -800);
DISPLAY INVISIBLE (2725 -800);
FORCEPROP 2 LAST PATH I214
J 0
(2575 -600);
DISPLAY 1.021277 (2575 -600);
DISPLAY INVISIBLE (2575 -600);
FORCEPROP 2 LAST CDS_LIB standard
J 0
(2400 -675);
DISPLAY INVISIBLE (2400 -675);
FORCEADD OFFPAGE..1
(-1250 75);
FORCEPROP 2 LAST $XR0 274 
J 0
(-1532 75);
DISPLAY 0.638298 (-1532 75);
PAINT MONO (-1532 75);
FORCEPROP 2 LAST CDS_LIB standard
J 0
(-1250 75);
DISPLAY INVISIBLE (-1250 75);
FORCEPROP 2 LAST PATH I215
J 0
(-1200 150);
DISPLAY 1.021277 (-1200 150);
DISPLAY INVISIBLE (-1200 150);
FORCEPROP 1 LAST COMMENT_BODY TRUE
J 0
(-1125 -25);
DISPLAY 1.170213 (-1125 -25);
PAINT GREEN (-1125 -25);
DISPLAY INVISIBLE (-1125 -25);
FORCEPROP 1 LAST OFFPAGE TRUE
J 0
(-925 -50);
DISPLAY 0.872340 (-925 -50);
DISPLAY INVISIBLE (-925 -50);
FORCEADD OFFPAGE..1
(-1250 25);
FORCEPROP 2 LAST $XR0 292 
J 0
(-1502 25);
DISPLAY 0.638298 (-1502 25);
PAINT MONO (-1502 25);
FORCEPROP 1 LAST OFFPAGE TRUE
J 0
(-925 -100);
DISPLAY 0.872340 (-925 -100);
DISPLAY INVISIBLE (-925 -100);
FORCEPROP 1 LAST COMMENT_BODY TRUE
J 0
(-1125 -75);
DISPLAY 1.170213 (-1125 -75);
PAINT GREEN (-1125 -75);
DISPLAY INVISIBLE (-1125 -75);
FORCEPROP 2 LAST PATH I216
J 0
(-1200 100);
DISPLAY 1.021277 (-1200 100);
DISPLAY INVISIBLE (-1200 100);
FORCEPROP 2 LAST CDS_LIB standard
J 0
(-1250 25);
DISPLAY INVISIBLE (-1250 25);
FORCEADD OFFPAGE..1
R 2
(2400 725);
FORCEPROP 2 LAST $XR0 220 
J 0
(2586 725);
DISPLAY 0.638298 (2586 725);
PAINT MONO (2586 725);
FORCEPROP 2 LAST PATH I22
J 0
(2600 775);
DISPLAY 1.021277 (2600 775);
DISPLAY INVISIBLE (2600 775);
FORCEPROP 2 LAST CDS_LIB standard
J 0
(2400 725);
DISPLAY INVISIBLE (2400 725);
FORCEPROP 1 LAST COMMENT_BODY TRUE
J 2
(2275 625);
DISPLAY 1.170213 (2275 625);
PAINT GREEN (2275 625);
DISPLAY INVISIBLE (2275 625);
FORCEPROP 1 LAST OFFPAGE TRUE
J 2
(2075 600);
DISPLAY 1.170213 (2075 600);
PAINT GREEN (2075 600);
DISPLAY INVISIBLE (2075 600);
FORCEADD OFFPAGE..2
(2400 625);
FORCEPROP 2 LAST $XR0 205 
J 0
(2589 625);
DISPLAY 0.638298 (2589 625);
PAINT MONO (2589 625);
FORCEPROP 2 LAST PATH I23
J 0
(2600 675);
DISPLAY 1.021277 (2600 675);
DISPLAY INVISIBLE (2600 675);
FORCEPROP 1 LAST OFFPAGE TRUE
J 0
(2725 500);
DISPLAY 1.170213 (2725 500);
PAINT GREEN (2725 500);
DISPLAY INVISIBLE (2725 500);
FORCEPROP 1 LAST COMMENT_BODY TRUE
J 0
(2355 530);
DISPLAY 1.170213 (2355 530);
PAINT GREEN (2355 530);
DISPLAY INVISIBLE (2355 530);
FORCEPROP 2 LAST CDS_LIB standard
J 0
(2400 625);
DISPLAY INVISIBLE (2400 625);
FORCEADD OFFPAGE..1
R 2
(2400 675);
FORCEPROP 2 LAST $XR0 220 
J 0
(2586 675);
DISPLAY 0.638298 (2586 675);
PAINT MONO (2586 675);
FORCEPROP 2 LAST PATH I24
J 0
(2600 725);
DISPLAY 1.021277 (2600 725);
DISPLAY INVISIBLE (2600 725);
FORCEPROP 1 LAST COMMENT_BODY TRUE
J 2
(2275 575);
DISPLAY 1.170213 (2275 575);
PAINT GREEN (2275 575);
DISPLAY INVISIBLE (2275 575);
FORCEPROP 1 LAST OFFPAGE TRUE
J 2
(2075 550);
DISPLAY 1.170213 (2075 550);
PAINT GREEN (2075 550);
DISPLAY INVISIBLE (2075 550);
FORCEPROP 2 LAST CDS_LIB standard
J 0
(2400 675);
DISPLAY INVISIBLE (2400 675);
FORCEADD OFFPAGE..1
R 2
(2400 525);
FORCEPROP 2 LAST $XR0 223 
J 0
(2586 525);
DISPLAY 0.638298 (2586 525);
PAINT MONO (2586 525);
FORCEPROP 2 LAST PATH I25
J 0
(2600 575);
DISPLAY 1.021277 (2600 575);
DISPLAY INVISIBLE (2600 575);
FORCEPROP 1 LAST COMMENT_BODY TRUE
J 2
(2275 425);
DISPLAY 1.170213 (2275 425);
PAINT GREEN (2275 425);
DISPLAY INVISIBLE (2275 425);
FORCEPROP 1 LAST OFFPAGE TRUE
J 2
(2075 400);
DISPLAY 1.170213 (2075 400);
PAINT GREEN (2075 400);
DISPLAY INVISIBLE (2075 400);
FORCEPROP 2 LAST CDS_LIB standard
J 0
(2400 525);
DISPLAY INVISIBLE (2400 525);
FORCEADD OFFPAGE..2
(2400 575);
FORCEPROP 2 LAST $XR0 214 
J 0
(2589 575);
DISPLAY 0.638298 (2589 575);
PAINT MONO (2589 575);
FORCEPROP 1 LAST COMMENT_BODY TRUE
J 0
(2355 480);
DISPLAY 1.170213 (2355 480);
PAINT GREEN (2355 480);
DISPLAY INVISIBLE (2355 480);
FORCEPROP 1 LAST OFFPAGE TRUE
J 0
(2725 450);
DISPLAY 1.170213 (2725 450);
PAINT GREEN (2725 450);
DISPLAY INVISIBLE (2725 450);
FORCEPROP 2 LAST PATH I26
J 0
(2600 625);
DISPLAY 1.021277 (2600 625);
DISPLAY INVISIBLE (2600 625);
FORCEPROP 2 LAST CDS_LIB standard
J 0
(2400 575);
DISPLAY INVISIBLE (2400 575);
FORCEADD OFFPAGE..2
(2400 475);
FORCEPROP 2 LAST $XR1 260 
J 0
(2709 475);
DISPLAY 0.638298 (2709 475);
PAINT MONO (2709 475);
FORCEPROP 2 LAST $XR0 224 
J 0
(2589 475);
DISPLAY 0.638298 (2589 475);
PAINT MONO (2589 475);
FORCEPROP 2 LAST PATH I27
J 0
(2600 525);
DISPLAY 1.021277 (2600 525);
DISPLAY INVISIBLE (2600 525);
FORCEPROP 2 LAST CDS_LIB standard
J 0
(2400 475);
DISPLAY INVISIBLE (2400 475);
FORCEPROP 1 LAST OFFPAGE TRUE
J 0
(2725 350);
DISPLAY 1.170213 (2725 350);
PAINT GREEN (2725 350);
DISPLAY INVISIBLE (2725 350);
FORCEPROP 1 LAST COMMENT_BODY TRUE
J 0
(2355 380);
DISPLAY 1.170213 (2355 380);
PAINT GREEN (2355 380);
DISPLAY INVISIBLE (2355 380);
FORCEADD OFFPAGE..3
(2400 375);
FORCEPROP 2 LAST $XR0 115 
J 0
(2614 375);
DISPLAY 0.638298 (2614 375);
PAINT MONO (2614 375);
FORCEPROP 2 LAST CDS_LIB standard
J 0
(2400 375);
DISPLAY INVISIBLE (2400 375);
FORCEPROP 1 LAST OFFPAGE TRUE
J 0
(2725 250);
DISPLAY 0.872340 (2725 250);
DISPLAY INVISIBLE (2725 250);
FORCEPROP 1 LAST COMMENT_BODY TRUE
J 0
(2350 275);
DISPLAY 0.872340 (2350 275);
PAINT GREEN (2350 275);
DISPLAY INVISIBLE (2350 275);
FORCEPROP 2 LAST PATH I28
J 0
(2625 425);
DISPLAY 1.021277 (2625 425);
DISPLAY INVISIBLE (2625 425);
FORCEADD OFFPAGE..3
(2400 425);
FORCEPROP 2 LAST $XR0 115 
J 0
(2614 425);
DISPLAY 0.638298 (2614 425);
PAINT MONO (2614 425);
FORCEPROP 1 LAST OFFPAGE TRUE
J 0
(2725 300);
DISPLAY 0.872340 (2725 300);
DISPLAY INVISIBLE (2725 300);
FORCEPROP 1 LAST COMMENT_BODY TRUE
J 0
(2350 325);
DISPLAY 0.872340 (2350 325);
PAINT GREEN (2350 325);
DISPLAY INVISIBLE (2350 325);
FORCEPROP 2 LAST CDS_LIB standard
J 0
(2400 425);
DISPLAY INVISIBLE (2400 425);
FORCEPROP 2 LAST PATH I29
J 0
(2625 475);
DISPLAY 1.021277 (2625 475);
DISPLAY INVISIBLE (2625 475);
FORCEADD OFFPAGE..1
R 2
(2400 1675);
FORCEPROP 2 LAST $XR0 241 
J 0
(2586 1675);
DISPLAY 0.638298 (2586 1675);
PAINT MONO (2586 1675);
FORCEPROP 2 LAST PATH I3
J 0
(2700 1725);
DISPLAY 1.021277 (2700 1725);
DISPLAY INVISIBLE (2700 1725);
FORCEPROP 1 LAST OFFPAGE TRUE
J 2
(2075 1550);
DISPLAY 1.170213 (2075 1550);
PAINT GREEN (2075 1550);
DISPLAY INVISIBLE (2075 1550);
FORCEPROP 1 LAST COMMENT_BODY TRUE
J 2
(2275 1575);
DISPLAY 1.170213 (2275 1575);
PAINT GREEN (2275 1575);
DISPLAY INVISIBLE (2275 1575);
FORCEPROP 2 LAST CDS_LIB standard
J 0
(2400 1675);
PAINT MONO (2400 1675);
DISPLAY INVISIBLE (2400 1675);
FORCEADD OFFPAGE..3
(2400 325);
FORCEPROP 2 LAST $XR0 115 
J 0
(2614 325);
DISPLAY 0.638298 (2614 325);
PAINT MONO (2614 325);
FORCEPROP 2 LAST CDS_LIB standard
J 0
(2400 325);
DISPLAY INVISIBLE (2400 325);
FORCEPROP 1 LAST OFFPAGE TRUE
J 0
(2725 200);
DISPLAY 0.872340 (2725 200);
DISPLAY INVISIBLE (2725 200);
FORCEPROP 1 LAST COMMENT_BODY TRUE
J 0
(2350 225);
DISPLAY 0.872340 (2350 225);
PAINT GREEN (2350 225);
DISPLAY INVISIBLE (2350 225);
FORCEPROP 2 LAST PATH I30
J 0
(2625 375);
DISPLAY 1.021277 (2625 375);
DISPLAY INVISIBLE (2625 375);
FORCEADD OFFPAGE..3
(2400 225);
FORCEPROP 2 LAST $XR0 115 
J 0
(2614 225);
DISPLAY 0.638298 (2614 225);
PAINT MONO (2614 225);
FORCEPROP 1 LAST COMMENT_BODY TRUE
J 0
(2350 125);
DISPLAY 0.872340 (2350 125);
PAINT GREEN (2350 125);
DISPLAY INVISIBLE (2350 125);
FORCEPROP 1 LAST OFFPAGE TRUE
J 0
(2725 100);
DISPLAY 0.872340 (2725 100);
DISPLAY INVISIBLE (2725 100);
FORCEPROP 2 LAST CDS_LIB standard
J 0
(2400 225);
DISPLAY INVISIBLE (2400 225);
FORCEPROP 2 LAST PATH I31
J 0
(2625 275);
DISPLAY 1.021277 (2625 275);
DISPLAY INVISIBLE (2625 275);
FORCEADD OFFPAGE..3
(2400 125);
FORCEPROP 2 LAST $XR0 115 
J 0
(2614 125);
DISPLAY 0.638298 (2614 125);
PAINT MONO (2614 125);
FORCEPROP 1 LAST COMMENT_BODY TRUE
J 0
(2350 25);
DISPLAY 0.872340 (2350 25);
PAINT GREEN (2350 25);
DISPLAY INVISIBLE (2350 25);
FORCEPROP 1 LAST OFFPAGE TRUE
J 0
(2725 0);
DISPLAY 0.872340 (2725 0);
DISPLAY INVISIBLE (2725 0);
FORCEPROP 2 LAST CDS_LIB standard
J 0
(2400 125);
DISPLAY INVISIBLE (2400 125);
FORCEPROP 2 LAST PATH I32
J 0
(2625 175);
DISPLAY 1.021277 (2625 175);
DISPLAY INVISIBLE (2625 175);
FORCEADD OFFPAGE..3
(2400 175);
FORCEPROP 2 LAST $XR0 115 
J 0
(2614 175);
DISPLAY 0.638298 (2614 175);
PAINT MONO (2614 175);
FORCEPROP 1 LAST OFFPAGE TRUE
J 0
(2725 50);
DISPLAY 0.872340 (2725 50);
DISPLAY INVISIBLE (2725 50);
FORCEPROP 1 LAST COMMENT_BODY TRUE
J 0
(2350 75);
DISPLAY 0.872340 (2350 75);
PAINT GREEN (2350 75);
DISPLAY INVISIBLE (2350 75);
FORCEPROP 2 LAST CDS_LIB standard
J 0
(2400 175);
DISPLAY INVISIBLE (2400 175);
FORCEPROP 2 LAST PATH I33
J 0
(2625 225);
DISPLAY 1.021277 (2625 225);
DISPLAY INVISIBLE (2625 225);
FORCEADD OFFPAGE..2
R 2
(-1250 1675);
FORCEPROP 2 LAST $XR1 278 
J 0
(-1655 1675);
DISPLAY 0.638298 (-1655 1675);
PAINT MONO (-1655 1675);
FORCEPROP 2 LAST $XR0 219 
J 0
(-1535 1675);
DISPLAY 0.638298 (-1535 1675);
PAINT MONO (-1535 1675);
FORCEPROP 2 LAST PATH I34
J 0
(-1500 1725);
DISPLAY 1.021277 (-1500 1725);
DISPLAY INVISIBLE (-1500 1725);
FORCEPROP 1 LAST OFFPAGE TRUE
J 2
(-1575 1550);
DISPLAY 1.170213 (-1575 1550);
PAINT GREEN (-1575 1550);
DISPLAY INVISIBLE (-1575 1550);
FORCEPROP 1 LAST COMMENT_BODY TRUE
J 2
(-1205 1580);
DISPLAY 1.170213 (-1205 1580);
PAINT GREEN (-1205 1580);
DISPLAY INVISIBLE (-1205 1580);
FORCEPROP 2 LAST CDS_LIB standard
J 2
(-1250 1675);
DISPLAY INVISIBLE (-1250 1675);
FORCEADD OFFPAGE..2
R 2
(-1250 1625);
FORCEPROP 2 LAST $XR1 296 
J 0
(-1655 1625);
DISPLAY 0.638298 (-1655 1625);
PAINT MONO (-1655 1625);
FORCEPROP 2 LAST $XR0 219 
J 0
(-1535 1625);
DISPLAY 0.638298 (-1535 1625);
PAINT MONO (-1535 1625);
FORCEPROP 2 LAST PATH I35
J 0
(-1500 1675);
DISPLAY 1.021277 (-1500 1675);
DISPLAY INVISIBLE (-1500 1675);
FORCEPROP 2 LAST CDS_LIB standard
J 2
(-1250 1625);
DISPLAY INVISIBLE (-1250 1625);
FORCEPROP 1 LAST OFFPAGE TRUE
J 2
(-1575 1500);
DISPLAY 1.170213 (-1575 1500);
PAINT GREEN (-1575 1500);
DISPLAY INVISIBLE (-1575 1500);
FORCEPROP 1 LAST COMMENT_BODY TRUE
J 2
(-1205 1530);
DISPLAY 1.170213 (-1205 1530);
PAINT GREEN (-1205 1530);
DISPLAY INVISIBLE (-1205 1530);
FORCEADD OFFPAGE..5
(-1250 1575);
FORCEPROP 2 LAST $XR1 222 
J 0
(-1655 1575);
DISPLAY 0.638298 (-1655 1575);
PAINT MONO (-1655 1575);
FORCEPROP 2 LAST $XR0 219 
J 0
(-1535 1575);
DISPLAY 0.638298 (-1535 1575);
PAINT MONO (-1535 1575);
FORCEPROP 2 LAST PATH I36
J 0
(-1500 1625);
DISPLAY 1.021277 (-1500 1625);
DISPLAY INVISIBLE (-1500 1625);
FORCEPROP 1 LAST COMMENT_BODY TRUE
J 0
(-1150 1500);
DISPLAY 1.170213 (-1150 1500);
PAINT GREEN (-1150 1500);
DISPLAY INVISIBLE (-1150 1500);
FORCEPROP 1 LAST OFFPAGE TRUE
J 0
(-925 1450);
DISPLAY 0.872340 (-925 1450);
DISPLAY INVISIBLE (-925 1450);
FORCEPROP 2 LAST CDS_LIB standard
J 0
(-1250 1575);
PAINT MONO (-1250 1575);
DISPLAY INVISIBLE (-1250 1575);
FORCEADD OFFPAGE..2
R 2
(-1250 1525);
FORCEPROP 2 LAST $XR1 222 
J 0
(-1655 1525);
DISPLAY 0.638298 (-1655 1525);
PAINT MONO (-1655 1525);
FORCEPROP 2 LAST $XR0 219 
J 0
(-1535 1525);
DISPLAY 0.638298 (-1535 1525);
PAINT MONO (-1535 1525);
FORCEPROP 2 LAST PATH I37
J 0
(-1500 1575);
DISPLAY 1.021277 (-1500 1575);
DISPLAY INVISIBLE (-1500 1575);
FORCEPROP 2 LAST CDS_LIB standard
J 2
(-1250 1525);
PAINT MONO (-1250 1525);
DISPLAY INVISIBLE (-1250 1525);
FORCEPROP 1 LAST COMMENT_BODY TRUE
J 2
(-1205 1430);
DISPLAY 1.170213 (-1205 1430);
PAINT GREEN (-1205 1430);
DISPLAY INVISIBLE (-1205 1430);
FORCEPROP 1 LAST OFFPAGE TRUE
J 2
(-1575 1400);
DISPLAY 1.170213 (-1575 1400);
PAINT GREEN (-1575 1400);
DISPLAY INVISIBLE (-1575 1400);
FORCEADD OFFPAGE..2
R 2
(-1250 1475);
FORCEPROP 2 LAST $XR1 222 
J 0
(-1655 1475);
DISPLAY 0.638298 (-1655 1475);
PAINT MONO (-1655 1475);
FORCEPROP 2 LAST $XR0 219 
J 0
(-1535 1475);
DISPLAY 0.638298 (-1535 1475);
PAINT MONO (-1535 1475);
FORCEPROP 2 LAST PATH I38
J 0
(-1500 1525);
DISPLAY 1.021277 (-1500 1525);
DISPLAY INVISIBLE (-1500 1525);
FORCEPROP 1 LAST OFFPAGE TRUE
J 2
(-1575 1350);
DISPLAY 1.170213 (-1575 1350);
PAINT GREEN (-1575 1350);
DISPLAY INVISIBLE (-1575 1350);
FORCEPROP 1 LAST COMMENT_BODY TRUE
J 2
(-1205 1380);
DISPLAY 1.170213 (-1205 1380);
PAINT GREEN (-1205 1380);
DISPLAY INVISIBLE (-1205 1380);
FORCEPROP 2 LAST CDS_LIB standard
J 2
(-1250 1475);
DISPLAY INVISIBLE (-1250 1475);
FORCEADD OFFPAGE..2
R 2
(-1250 1425);
FORCEPROP 2 LAST $XR1 222 
J 0
(-1655 1425);
DISPLAY 0.638298 (-1655 1425);
PAINT MONO (-1655 1425);
FORCEPROP 2 LAST $XR0 219 
J 0
(-1535 1425);
DISPLAY 0.638298 (-1535 1425);
PAINT MONO (-1535 1425);
FORCEPROP 2 LAST PATH I39
J 0
(-1500 1475);
DISPLAY 1.021277 (-1500 1475);
DISPLAY INVISIBLE (-1500 1475);
FORCEPROP 2 LAST CDS_LIB standard
J 2
(-1250 1425);
DISPLAY INVISIBLE (-1250 1425);
FORCEPROP 1 LAST OFFPAGE TRUE
J 2
(-1575 1300);
DISPLAY 1.170213 (-1575 1300);
PAINT GREEN (-1575 1300);
DISPLAY INVISIBLE (-1575 1300);
FORCEPROP 1 LAST COMMENT_BODY TRUE
J 2
(-1205 1330);
DISPLAY 1.170213 (-1205 1330);
PAINT GREEN (-1205 1330);
DISPLAY INVISIBLE (-1205 1330);
FORCEADD OFFPAGE..6
R 2
(2400 1625);
FORCEPROP 2 LAST $XR0 241 
J 0
(2614 1625);
DISPLAY 0.638298 (2614 1625);
PAINT MONO (2614 1625);
FORCEPROP 2 LAST PATH I4
J 0
(2725 1675);
DISPLAY 1.021277 (2725 1675);
DISPLAY INVISIBLE (2725 1675);
FORCEPROP 1 LAST COMMENT_BODY TRUE
J 2
(2300 1550);
DISPLAY 0.872340 (2300 1550);
PAINT GREEN (2300 1550);
DISPLAY INVISIBLE (2300 1550);
FORCEPROP 1 LAST OFFPAGE TRUE
J 2
(2075 1500);
DISPLAY 0.872340 (2075 1500);
DISPLAY INVISIBLE (2075 1500);
FORCEPROP 2 LAST CDS_LIB standard
J 0
(2400 1625);
PAINT MONO (2400 1625);
DISPLAY INVISIBLE (2400 1625);
FORCEADD OFFPAGE..5
(-1250 1375);
FORCEPROP 2 LAST $XR1 222 
J 0
(-1655 1375);
DISPLAY 0.638298 (-1655 1375);
PAINT MONO (-1655 1375);
FORCEPROP 2 LAST $XR0 219 
J 0
(-1535 1375);
DISPLAY 0.638298 (-1535 1375);
PAINT MONO (-1535 1375);
FORCEPROP 2 LAST PATH I40
J 0
(-1500 1425);
DISPLAY 1.021277 (-1500 1425);
DISPLAY INVISIBLE (-1500 1425);
FORCEPROP 1 LAST OFFPAGE TRUE
J 0
(-925 1250);
DISPLAY 0.872340 (-925 1250);
DISPLAY INVISIBLE (-925 1250);
FORCEPROP 1 LAST COMMENT_BODY TRUE
J 0
(-1150 1300);
DISPLAY 1.170213 (-1150 1300);
PAINT GREEN (-1150 1300);
DISPLAY INVISIBLE (-1150 1300);
FORCEPROP 2 LAST CDS_LIB standard
J 0
(-1250 1375);
DISPLAY INVISIBLE (-1250 1375);
FORCEADD OFFPAGE..2
R 2
(-1250 1275);
FORCEPROP 2 LAST $XR0 282 
J 0
(-1535 1275);
DISPLAY 0.638298 (-1535 1275);
PAINT MONO (-1535 1275);
FORCEPROP 2 LAST PATH I41
J 0
(-1500 1325);
DISPLAY 1.021277 (-1500 1325);
DISPLAY INVISIBLE (-1500 1325);
FORCEPROP 2 LAST CDS_LIB standard
J 2
(-1250 1275);
DISPLAY INVISIBLE (-1250 1275);
FORCEPROP 1 LAST COMMENT_BODY TRUE
J 2
(-1205 1180);
DISPLAY 1.170213 (-1205 1180);
PAINT GREEN (-1205 1180);
DISPLAY INVISIBLE (-1205 1180);
FORCEPROP 1 LAST OFFPAGE TRUE
J 2
(-1575 1150);
DISPLAY 1.170213 (-1575 1150);
PAINT GREEN (-1575 1150);
DISPLAY INVISIBLE (-1575 1150);
FORCEADD OFFPAGE..2
R 2
(-1250 1325);
FORCEPROP 2 LAST $XR1 222 
J 0
(-1655 1325);
DISPLAY 0.638298 (-1655 1325);
PAINT MONO (-1655 1325);
FORCEPROP 2 LAST $XR0 219 
J 0
(-1535 1325);
DISPLAY 0.638298 (-1535 1325);
PAINT MONO (-1535 1325);
FORCEPROP 2 LAST PATH I42
J 0
(-1500 1375);
DISPLAY 1.021277 (-1500 1375);
DISPLAY INVISIBLE (-1500 1375);
FORCEPROP 2 LAST CDS_LIB standard
J 2
(-1250 1325);
DISPLAY INVISIBLE (-1250 1325);
FORCEPROP 1 LAST COMMENT_BODY TRUE
J 2
(-1205 1230);
DISPLAY 1.170213 (-1205 1230);
PAINT GREEN (-1205 1230);
DISPLAY INVISIBLE (-1205 1230);
FORCEPROP 1 LAST OFFPAGE TRUE
J 2
(-1575 1200);
DISPLAY 1.170213 (-1575 1200);
PAINT GREEN (-1575 1200);
DISPLAY INVISIBLE (-1575 1200);
FORCEADD OFFPAGE..2
R 2
(-1250 1225);
FORCEPROP 2 LAST $XR0 300 
J 0
(-1535 1225);
DISPLAY 0.638298 (-1535 1225);
PAINT MONO (-1535 1225);
FORCEPROP 2 LAST PATH I43
J 0
(-1500 1275);
DISPLAY 1.021277 (-1500 1275);
DISPLAY INVISIBLE (-1500 1275);
FORCEPROP 1 LAST COMMENT_BODY TRUE
J 2
(-1205 1130);
DISPLAY 1.170213 (-1205 1130);
PAINT GREEN (-1205 1130);
DISPLAY INVISIBLE (-1205 1130);
FORCEPROP 1 LAST OFFPAGE TRUE
J 2
(-1575 1100);
DISPLAY 1.170213 (-1575 1100);
PAINT GREEN (-1575 1100);
DISPLAY INVISIBLE (-1575 1100);
FORCEPROP 2 LAST CDS_LIB standard
J 2
(-1250 1225);
DISPLAY INVISIBLE (-1250 1225);
FORCEADD OFFPAGE..5
(-1250 1175);
FORCEPROP 2 LAST $XR1 222 
J 0
(-1655 1175);
DISPLAY 0.638298 (-1655 1175);
PAINT MONO (-1655 1175);
FORCEPROP 2 LAST $XR0 219 
J 0
(-1535 1175);
DISPLAY 0.638298 (-1535 1175);
PAINT MONO (-1535 1175);
FORCEPROP 2 LAST PATH I44
J 0
(-1500 1225);
DISPLAY 1.021277 (-1500 1225);
DISPLAY INVISIBLE (-1500 1225);
FORCEPROP 1 LAST COMMENT_BODY TRUE
J 0
(-1150 1100);
DISPLAY 1.170213 (-1150 1100);
PAINT GREEN (-1150 1100);
DISPLAY INVISIBLE (-1150 1100);
FORCEPROP 1 LAST OFFPAGE TRUE
J 0
(-925 1050);
DISPLAY 0.872340 (-925 1050);
DISPLAY INVISIBLE (-925 1050);
FORCEPROP 2 LAST CDS_LIB standard
J 0
(-1250 1175);
DISPLAY INVISIBLE (-1250 1175);
FORCEADD OFFPAGE..5
(-1250 1125);
FORCEPROP 2 LAST $XR1 222 
J 0
(-1655 1125);
DISPLAY 0.638298 (-1655 1125);
PAINT MONO (-1655 1125);
FORCEPROP 2 LAST $XR0 219 
J 0
(-1535 1125);
DISPLAY 0.638298 (-1535 1125);
PAINT MONO (-1535 1125);
FORCEPROP 2 LAST PATH I45
J 0
(-1500 1175);
DISPLAY 1.021277 (-1500 1175);
DISPLAY INVISIBLE (-1500 1175);
FORCEPROP 1 LAST OFFPAGE TRUE
J 0
(-925 1000);
DISPLAY 0.872340 (-925 1000);
DISPLAY INVISIBLE (-925 1000);
FORCEPROP 1 LAST COMMENT_BODY TRUE
J 0
(-1150 1050);
DISPLAY 1.170213 (-1150 1050);
PAINT GREEN (-1150 1050);
DISPLAY INVISIBLE (-1150 1050);
FORCEPROP 2 LAST CDS_LIB standard
J 0
(-1250 1125);
DISPLAY INVISIBLE (-1250 1125);
FORCEADD OFFPAGE..2
R 2
(-1250 1025);
FORCEPROP 2 LAST $XR0 281 
J 0
(-1535 1025);
DISPLAY 0.638298 (-1535 1025);
PAINT MONO (-1535 1025);
FORCEPROP 2 LAST PATH I46
J 0
(-1500 1075);
DISPLAY 1.021277 (-1500 1075);
DISPLAY INVISIBLE (-1500 1075);
FORCEPROP 2 LAST CDS_LIB standard
J 2
(-1250 1025);
DISPLAY INVISIBLE (-1250 1025);
FORCEPROP 1 LAST COMMENT_BODY TRUE
J 2
(-1205 930);
DISPLAY 1.170213 (-1205 930);
PAINT GREEN (-1205 930);
DISPLAY INVISIBLE (-1205 930);
FORCEPROP 1 LAST OFFPAGE TRUE
J 2
(-1575 900);
DISPLAY 1.170213 (-1575 900);
PAINT GREEN (-1575 900);
DISPLAY INVISIBLE (-1575 900);
FORCEADD OFFPAGE..5
(-1250 1075);
FORCEPROP 2 LAST $XR0 299 
J 0
(-1535 1075);
DISPLAY 0.638298 (-1535 1075);
PAINT MONO (-1535 1075);
FORCEPROP 2 LAST PATH I47
J 0
(-1500 1125);
DISPLAY 1.021277 (-1500 1125);
DISPLAY INVISIBLE (-1500 1125);
FORCEPROP 2 LAST CDS_LIB standard
J 0
(-1250 1075);
PAINT MONO (-1250 1075);
DISPLAY INVISIBLE (-1250 1075);
FORCEPROP 1 LAST OFFPAGE TRUE
J 0
(-925 950);
DISPLAY 0.872340 (-925 950);
DISPLAY INVISIBLE (-925 950);
FORCEPROP 1 LAST COMMENT_BODY TRUE
J 0
(-1150 1000);
DISPLAY 1.170213 (-1150 1000);
PAINT GREEN (-1150 1000);
DISPLAY INVISIBLE (-1150 1000);
FORCEADD OFFPAGE..5
(-1250 975);
FORCEPROP 2 LAST $XR0 219 
J 0
(-1535 975);
DISPLAY 0.638298 (-1535 975);
PAINT MONO (-1535 975);
FORCEPROP 2 LAST PATH I48
J 0
(-1500 1025);
DISPLAY 1.021277 (-1500 1025);
DISPLAY INVISIBLE (-1500 1025);
FORCEPROP 2 LAST CDS_LIB standard
J 0
(-1250 975);
DISPLAY INVISIBLE (-1250 975);
FORCEPROP 1 LAST COMMENT_BODY TRUE
J 0
(-1150 900);
DISPLAY 1.170213 (-1150 900);
PAINT GREEN (-1150 900);
DISPLAY INVISIBLE (-1150 900);
FORCEPROP 1 LAST OFFPAGE TRUE
J 0
(-925 850);
DISPLAY 0.872340 (-925 850);
DISPLAY INVISIBLE (-925 850);
FORCEADD OFFPAGE..5
(-1250 925);
FORCEPROP 2 LAST $XR1 263 
J 0
(-1655 925);
DISPLAY 0.638298 (-1655 925);
PAINT MONO (-1655 925);
FORCEPROP 2 LAST $XR0 219 
J 0
(-1535 925);
DISPLAY 0.638298 (-1535 925);
PAINT MONO (-1535 925);
FORCEPROP 2 LAST PATH I49
J 0
(-1500 975);
DISPLAY 1.021277 (-1500 975);
DISPLAY INVISIBLE (-1500 975);
FORCEPROP 2 LAST CDS_LIB standard
J 0
(-1250 925);
DISPLAY INVISIBLE (-1250 925);
FORCEPROP 1 LAST COMMENT_BODY TRUE
J 0
(-1150 850);
DISPLAY 1.170213 (-1150 850);
PAINT GREEN (-1150 850);
DISPLAY INVISIBLE (-1150 850);
FORCEPROP 1 LAST OFFPAGE TRUE
J 0
(-925 800);
DISPLAY 0.872340 (-925 800);
DISPLAY INVISIBLE (-925 800);
FORCEADD OFFPAGE..2
(2400 1575);
FORCEPROP 2 LAST $XR1 223 
J 0
(2709 1575);
DISPLAY 0.638298 (2709 1575);
PAINT MONO (2709 1575);
FORCEPROP 2 LAST $XR0 219 
J 0
(2589 1575);
DISPLAY 0.638298 (2589 1575);
PAINT MONO (2589 1575);
FORCEPROP 2 LAST PATH I5
J 0
(2725 1625);
DISPLAY 1.021277 (2725 1625);
DISPLAY INVISIBLE (2725 1625);
FORCEPROP 2 LAST CDS_LIB standard
J 0
(2400 1575);
DISPLAY INVISIBLE (2400 1575);
FORCEPROP 1 LAST OFFPAGE TRUE
J 0
(2725 1450);
DISPLAY 1.170213 (2725 1450);
PAINT GREEN (2725 1450);
DISPLAY INVISIBLE (2725 1450);
FORCEPROP 1 LAST COMMENT_BODY TRUE
J 0
(2355 1480);
DISPLAY 1.170213 (2355 1480);
PAINT GREEN (2355 1480);
DISPLAY INVISIBLE (2355 1480);
FORCEADD OFFPAGE..5
(-1250 875);
FORCEPROP 2 LAST $XR0 260 
J 0
(-1535 875);
DISPLAY 0.638298 (-1535 875);
PAINT MONO (-1535 875);
FORCEPROP 2 LAST PATH I50
J 0
(-1500 925);
DISPLAY 1.021277 (-1500 925);
DISPLAY INVISIBLE (-1500 925);
FORCEPROP 2 LAST CDS_LIB standard
J 0
(-1250 875);
PAINT MONO (-1250 875);
DISPLAY INVISIBLE (-1250 875);
FORCEPROP 1 LAST OFFPAGE TRUE
J 0
(-925 750);
DISPLAY 0.872340 (-925 750);
DISPLAY INVISIBLE (-925 750);
FORCEPROP 1 LAST COMMENT_BODY TRUE
J 0
(-1150 800);
DISPLAY 1.170213 (-1150 800);
PAINT GREEN (-1150 800);
DISPLAY INVISIBLE (-1150 800);
FORCEADD OFFPAGE..5
(-1250 825);
FORCEPROP 2 LAST $XR0 262 
J 0
(-1535 825);
DISPLAY 0.638298 (-1535 825);
PAINT MONO (-1535 825);
FORCEPROP 2 LAST PATH I51
J 0
(-1500 875);
DISPLAY 1.021277 (-1500 875);
DISPLAY INVISIBLE (-1500 875);
FORCEPROP 1 LAST OFFPAGE TRUE
J 0
(-925 700);
DISPLAY 0.872340 (-925 700);
DISPLAY INVISIBLE (-925 700);
FORCEPROP 1 LAST COMMENT_BODY TRUE
J 0
(-1150 750);
DISPLAY 1.170213 (-1150 750);
PAINT GREEN (-1150 750);
DISPLAY INVISIBLE (-1150 750);
FORCEPROP 2 LAST CDS_LIB standard
J 0
(-1250 825);
DISPLAY INVISIBLE (-1250 825);
FORCEADD OFFPAGE..5
(-1250 775);
FORCEPROP 2 LAST $XR0 214 
J 0
(-1535 775);
DISPLAY 0.638298 (-1535 775);
PAINT MONO (-1535 775);
FORCEPROP 2 LAST PATH I52
J 0
(-1500 825);
DISPLAY 1.021277 (-1500 825);
DISPLAY INVISIBLE (-1500 825);
FORCEPROP 2 LAST CDS_LIB standard
J 0
(-1250 775);
DISPLAY INVISIBLE (-1250 775);
FORCEPROP 1 LAST OFFPAGE TRUE
J 0
(-925 650);
DISPLAY 0.872340 (-925 650);
DISPLAY INVISIBLE (-925 650);
FORCEPROP 1 LAST COMMENT_BODY TRUE
J 0
(-1150 700);
DISPLAY 1.170213 (-1150 700);
PAINT GREEN (-1150 700);
DISPLAY INVISIBLE (-1150 700);
FORCEADD OFFPAGE..2
R 2
(-1250 725);
FORCEPROP 2 LAST $XR1 254 
J 0
(-1655 725);
DISPLAY 0.638298 (-1655 725);
PAINT MONO (-1655 725);
FORCEPROP 2 LAST $XR0 284 
J 0
(-1535 725);
DISPLAY 0.638298 (-1535 725);
PAINT MONO (-1535 725);
FORCEPROP 2 LAST PATH I53
J 0
(-1500 775);
DISPLAY 1.021277 (-1500 775);
DISPLAY INVISIBLE (-1500 775);
FORCEPROP 2 LAST CDS_LIB standard
J 2
(-1250 725);
DISPLAY INVISIBLE (-1250 725);
FORCEPROP 1 LAST OFFPAGE TRUE
J 2
(-1575 600);
DISPLAY 1.170213 (-1575 600);
PAINT GREEN (-1575 600);
DISPLAY INVISIBLE (-1575 600);
FORCEPROP 1 LAST COMMENT_BODY TRUE
J 2
(-1205 630);
DISPLAY 1.170213 (-1205 630);
PAINT GREEN (-1205 630);
DISPLAY INVISIBLE (-1205 630);
FORCEADD OFFPAGE..1
(-1250 625);
FORCEPROP 2 LAST $XR1 254 
J 0
(-1622 625);
DISPLAY 0.638298 (-1622 625);
PAINT MONO (-1622 625);
FORCEPROP 2 LAST $XR0 292 
J 0
(-1502 625);
DISPLAY 0.638298 (-1502 625);
PAINT MONO (-1502 625);
FORCEPROP 2 LAST CDS_LIB standard
J 0
(-1250 625);
DISPLAY INVISIBLE (-1250 625);
FORCEPROP 1 LAST OFFPAGE TRUE
J 0
(-925 500);
DISPLAY 0.872340 (-925 500);
DISPLAY INVISIBLE (-925 500);
FORCEPROP 1 LAST COMMENT_BODY TRUE
J 0
(-1125 525);
DISPLAY 1.170213 (-1125 525);
PAINT GREEN (-1125 525);
DISPLAY INVISIBLE (-1125 525);
FORCEPROP 2 LAST PATH I54
J 0
(-1525 675);
DISPLAY 1.021277 (-1525 675);
DISPLAY INVISIBLE (-1525 675);
FORCEADD OFFPAGE..1
(-1250 675);
FORCEPROP 2 LAST $XR1 253 
J 0
(-1652 675);
DISPLAY 0.638298 (-1652 675);
PAINT MONO (-1652 675);
FORCEPROP 2 LAST $XR0 274 
J 0
(-1532 675);
DISPLAY 0.638298 (-1532 675);
PAINT MONO (-1532 675);
FORCEPROP 2 LAST CDS_LIB standard
J 0
(-1250 675);
DISPLAY INVISIBLE (-1250 675);
FORCEPROP 1 LAST OFFPAGE TRUE
J 0
(-925 550);
DISPLAY 0.872340 (-925 550);
DISPLAY INVISIBLE (-925 550);
FORCEPROP 1 LAST COMMENT_BODY TRUE
J 0
(-1125 575);
DISPLAY 1.170213 (-1125 575);
PAINT GREEN (-1125 575);
DISPLAY INVISIBLE (-1125 575);
FORCEPROP 2 LAST PATH I55
J 0
(-1525 725);
DISPLAY 1.021277 (-1525 725);
DISPLAY INVISIBLE (-1525 725);
FORCEADD OFFPAGE..1
(-1250 575);
FORCEPROP 2 LAST $XR1 253 
J 0
(-1622 575);
DISPLAY 0.638298 (-1622 575);
PAINT MONO (-1622 575);
FORCEPROP 2 LAST $XR0 274 
J 0
(-1502 575);
DISPLAY 0.638298 (-1502 575);
PAINT MONO (-1502 575);
FORCEPROP 1 LAST COMMENT_BODY TRUE
J 0
(-1125 475);
DISPLAY 1.170213 (-1125 475);
PAINT GREEN (-1125 475);
DISPLAY INVISIBLE (-1125 475);
FORCEPROP 1 LAST OFFPAGE TRUE
J 0
(-925 450);
DISPLAY 0.872340 (-925 450);
DISPLAY INVISIBLE (-925 450);
FORCEPROP 2 LAST CDS_LIB standard
J 0
(-1250 575);
DISPLAY INVISIBLE (-1250 575);
FORCEPROP 2 LAST PATH I56
J 0
(-1525 625);
DISPLAY 1.021277 (-1525 625);
DISPLAY INVISIBLE (-1525 625);
FORCEADD OFFPAGE..1
(-1250 525);
FORCEPROP 2 LAST $XR1 254 
J 0
(-1622 525);
DISPLAY 0.638298 (-1622 525);
PAINT MONO (-1622 525);
FORCEPROP 2 LAST $XR0 292 
J 0
(-1502 525);
DISPLAY 0.638298 (-1502 525);
PAINT MONO (-1502 525);
FORCEPROP 1 LAST COMMENT_BODY TRUE
J 0
(-1125 425);
DISPLAY 1.170213 (-1125 425);
PAINT GREEN (-1125 425);
DISPLAY INVISIBLE (-1125 425);
FORCEPROP 1 LAST OFFPAGE TRUE
J 0
(-925 400);
DISPLAY 1.170213 (-925 400);
PAINT GREEN (-925 400);
DISPLAY INVISIBLE (-925 400);
FORCEPROP 2 LAST CDS_LIB standard
J 2
(-1250 525);
DISPLAY INVISIBLE (-1250 525);
FORCEPROP 2 LAST PATH I57
J 0
(-1525 575);
DISPLAY 1.021277 (-1525 575);
DISPLAY INVISIBLE (-1525 575);
FORCEADD OFFPAGE..1
(-1250 475);
FORCEPROP 2 LAST $XR1 254 
J 0
(-1622 475);
DISPLAY 0.638298 (-1622 475);
PAINT MONO (-1622 475);
FORCEPROP 2 LAST $XR0 284 
J 0
(-1502 475);
DISPLAY 0.638298 (-1502 475);
PAINT MONO (-1502 475);
FORCEPROP 1 LAST COMMENT_BODY TRUE
J 0
(-1125 375);
DISPLAY 1.170213 (-1125 375);
PAINT GREEN (-1125 375);
DISPLAY INVISIBLE (-1125 375);
FORCEPROP 1 LAST OFFPAGE TRUE
J 0
(-925 350);
DISPLAY 0.872340 (-925 350);
DISPLAY INVISIBLE (-925 350);
FORCEPROP 2 LAST CDS_LIB standard
J 0
(-1250 475);
PAINT MONO (-1250 475);
DISPLAY INVISIBLE (-1250 475);
FORCEPROP 2 LAST PATH I58
J 0
(-1525 525);
DISPLAY 1.021277 (-1525 525);
DISPLAY INVISIBLE (-1525 525);
FORCEADD OFFPAGE..2
R 2
(-1250 375);
FORCEPROP 2 LAST $XR1 244 
J 0
(-1655 375);
DISPLAY 0.638298 (-1655 375);
PAINT MONO (-1655 375);
FORCEPROP 2 LAST $XR0 220 
J 0
(-1535 375);
DISPLAY 0.638298 (-1535 375);
PAINT MONO (-1535 375);
FORCEPROP 2 LAST PATH I59
J 0
(-1500 425);
DISPLAY 1.021277 (-1500 425);
DISPLAY INVISIBLE (-1500 425);
FORCEPROP 1 LAST OFFPAGE TRUE
J 2
(-1575 250);
DISPLAY 1.170213 (-1575 250);
PAINT GREEN (-1575 250);
DISPLAY INVISIBLE (-1575 250);
FORCEPROP 1 LAST COMMENT_BODY TRUE
J 2
(-1205 280);
DISPLAY 1.170213 (-1205 280);
PAINT GREEN (-1205 280);
DISPLAY INVISIBLE (-1205 280);
FORCEPROP 2 LAST CDS_LIB standard
J 2
(-1250 375);
DISPLAY INVISIBLE (-1250 375);
FORCEADD OFFPAGE..2
(2400 1525);
FORCEPROP 2 LAST $XR1 223 
J 0
(2709 1525);
DISPLAY 0.638298 (2709 1525);
PAINT MONO (2709 1525);
FORCEPROP 2 LAST $XR0 219 
J 0
(2589 1525);
DISPLAY 0.638298 (2589 1525);
PAINT MONO (2589 1525);
FORCEPROP 2 LAST PATH I6
J 0
(2725 1575);
DISPLAY 1.021277 (2725 1575);
DISPLAY INVISIBLE (2725 1575);
FORCEPROP 1 LAST OFFPAGE TRUE
J 0
(2725 1400);
DISPLAY 1.170213 (2725 1400);
PAINT GREEN (2725 1400);
DISPLAY INVISIBLE (2725 1400);
FORCEPROP 1 LAST COMMENT_BODY TRUE
J 0
(2355 1430);
DISPLAY 1.170213 (2355 1430);
PAINT GREEN (2355 1430);
DISPLAY INVISIBLE (2355 1430);
FORCEPROP 2 LAST CDS_LIB standard
J 0
(2400 1525);
DISPLAY INVISIBLE (2400 1525);
FORCEADD OFFPAGE..1
(-1250 425);
FORCEPROP 2 LAST $XR1 254 
J 0
(-1622 425);
DISPLAY 0.638298 (-1622 425);
PAINT MONO (-1622 425);
FORCEPROP 2 LAST $XR0 296 
J 0
(-1502 425);
DISPLAY 0.638298 (-1502 425);
PAINT MONO (-1502 425);
FORCEPROP 1 LAST OFFPAGE TRUE
J 0
(-925 300);
DISPLAY 0.872340 (-925 300);
DISPLAY INVISIBLE (-925 300);
FORCEPROP 1 LAST COMMENT_BODY TRUE
J 0
(-1125 325);
DISPLAY 1.170213 (-1125 325);
PAINT GREEN (-1125 325);
DISPLAY INVISIBLE (-1125 325);
FORCEPROP 2 LAST CDS_LIB standard
J 0
(-1250 425);
PAINT MONO (-1250 425);
DISPLAY INVISIBLE (-1250 425);
FORCEPROP 2 LAST PATH I60
J 0
(-1525 475);
DISPLAY 1.021277 (-1525 475);
DISPLAY INVISIBLE (-1525 475);
FORCEADD OFFPAGE..1
(-1250 325);
FORCEPROP 2 LAST $XR0 224 
J 0
(-1532 325);
DISPLAY 0.638298 (-1532 325);
PAINT MONO (-1532 325);
FORCEPROP 2 LAST PATH I61
J 0
(-1525 375);
DISPLAY 1.021277 (-1525 375);
DISPLAY INVISIBLE (-1525 375);
FORCEPROP 2 LAST CDS_LIB standard
J 2
(-1250 325);
DISPLAY INVISIBLE (-1250 325);
FORCEPROP 1 LAST COMMENT_BODY TRUE
J 0
(-1125 225);
DISPLAY 1.170213 (-1125 225);
PAINT GREEN (-1125 225);
DISPLAY INVISIBLE (-1125 225);
FORCEPROP 1 LAST OFFPAGE TRUE
J 0
(-925 200);
DISPLAY 1.170213 (-925 200);
PAINT GREEN (-925 200);
DISPLAY INVISIBLE (-925 200);
FORCEADD OFFPAGE..1
(-1250 275);
FORCEPROP 2 LAST $XR1 252 
J 0
(-1622 275);
DISPLAY 0.638298 (-1622 275);
PAINT MONO (-1622 275);
FORCEPROP 2 LAST $XR0 262 
J 0
(-1502 275);
DISPLAY 0.638298 (-1502 275);
PAINT MONO (-1502 275);
FORCEPROP 2 LAST PATH I62
J 0
(-1525 325);
DISPLAY 1.021277 (-1525 325);
DISPLAY INVISIBLE (-1525 325);
FORCEPROP 1 LAST COMMENT_BODY TRUE
J 0
(-1125 175);
DISPLAY 1.170213 (-1125 175);
PAINT GREEN (-1125 175);
DISPLAY INVISIBLE (-1125 175);
FORCEPROP 1 LAST OFFPAGE TRUE
J 0
(-925 150);
DISPLAY 0.872340 (-925 150);
DISPLAY INVISIBLE (-925 150);
FORCEPROP 2 LAST CDS_LIB standard
J 0
(-1250 275);
DISPLAY INVISIBLE (-1250 275);
FORCEADD OFFPAGE..1
(-1250 225);
FORCEPROP 2 LAST $XR0 222 
J 0
(-1502 225);
DISPLAY 0.638298 (-1502 225);
PAINT MONO (-1502 225);
FORCEPROP 2 LAST CDS_LIB standard
J 0
(-1250 225);
DISPLAY INVISIBLE (-1250 225);
FORCEPROP 2 LAST PATH I63
J 0
(-1525 275);
DISPLAY 1.021277 (-1525 275);
DISPLAY INVISIBLE (-1525 275);
FORCEPROP 1 LAST COMMENT_BODY TRUE
J 0
(-1125 125);
DISPLAY 1.170213 (-1125 125);
PAINT GREEN (-1125 125);
DISPLAY INVISIBLE (-1125 125);
FORCEPROP 1 LAST OFFPAGE TRUE
J 0
(-925 100);
DISPLAY 0.872340 (-925 100);
DISPLAY INVISIBLE (-925 100);
FORCEADD OFFPAGE..5
(-1250 175);
FORCEPROP 2 LAST $XR2 255 
J 0
(-1775 175);
DISPLAY 0.638298 (-1775 175);
PAINT MONO (-1775 175);
FORCEPROP 2 LAST $XR1 222 
J 0
(-1655 175);
DISPLAY 0.638298 (-1655 175);
PAINT MONO (-1655 175);
FORCEPROP 2 LAST $XR0 220 
J 0
(-1535 175);
DISPLAY 0.638298 (-1535 175);
PAINT MONO (-1535 175);
FORCEPROP 2 LAST PATH I64
J 0
(-1500 225);
DISPLAY 1.021277 (-1500 225);
DISPLAY INVISIBLE (-1500 225);
FORCEPROP 2 LAST CDS_LIB standard
J 0
(-1250 175);
PAINT MONO (-1250 175);
DISPLAY INVISIBLE (-1250 175);
FORCEPROP 1 LAST COMMENT_BODY TRUE
J 0
(-1150 100);
DISPLAY 1.170213 (-1150 100);
PAINT GREEN (-1150 100);
DISPLAY INVISIBLE (-1150 100);
FORCEPROP 1 LAST OFFPAGE TRUE
J 0
(-925 50);
DISPLAY 0.872340 (-925 50);
DISPLAY INVISIBLE (-925 50);
FORCEADD OFFPAGE..5
(-1250 125);
FORCEPROP 2 LAST $XR2 255 
J 0
(-1775 125);
DISPLAY 0.638298 (-1775 125);
PAINT MONO (-1775 125);
FORCEPROP 2 LAST $XR1 222 
J 0
(-1655 125);
DISPLAY 0.638298 (-1655 125);
PAINT MONO (-1655 125);
FORCEPROP 2 LAST $XR0 220 
J 0
(-1535 125);
DISPLAY 0.638298 (-1535 125);
PAINT MONO (-1535 125);
FORCEPROP 2 LAST PATH I65
J 0
(-1500 175);
DISPLAY 1.021277 (-1500 175);
DISPLAY INVISIBLE (-1500 175);
FORCEPROP 2 LAST CDS_LIB standard
J 0
(-1250 125);
PAINT MONO (-1250 125);
DISPLAY INVISIBLE (-1250 125);
FORCEPROP 1 LAST OFFPAGE TRUE
J 0
(-925 0);
DISPLAY 0.872340 (-925 0);
DISPLAY INVISIBLE (-925 0);
FORCEPROP 1 LAST COMMENT_BODY TRUE
J 0
(-1150 50);
DISPLAY 1.170213 (-1150 50);
PAINT GREEN (-1150 50);
DISPLAY INVISIBLE (-1150 50);
FORCEADD OFFPAGE..1
R 2
(2400 1475);
FORCEPROP 2 LAST $XR0 222 
J 0
(2586 1475);
DISPLAY 0.638298 (2586 1475);
PAINT MONO (2586 1475);
FORCEPROP 2 LAST PATH I7
J 0
(2600 1525);
DISPLAY 1.021277 (2600 1525);
DISPLAY INVISIBLE (2600 1525);
FORCEPROP 1 LAST COMMENT_BODY TRUE
J 2
(2275 1375);
DISPLAY 1.170213 (2275 1375);
PAINT GREEN (2275 1375);
DISPLAY INVISIBLE (2275 1375);
FORCEPROP 1 LAST OFFPAGE TRUE
J 2
(2075 1350);
DISPLAY 1.170213 (2075 1350);
PAINT GREEN (2075 1350);
DISPLAY INVISIBLE (2075 1350);
FORCEPROP 2 LAST CDS_LIB standard
J 0
(2400 1475);
DISPLAY INVISIBLE (2400 1475);
FORCEADD OFFPAGE..2
(4200 -1400);
FORCEPROP 2 LAST $XR0 214 
J 0
(4389 -1400);
DISPLAY 0.638298 (4389 -1400);
PAINT MONO (4389 -1400);
FORCEPROP 2 LAST CDS_LIB standard
J 0
(4200 -1400);
PAINT MONO (4200 -1400);
DISPLAY INVISIBLE (4200 -1400);
FORCEPROP 1 LAST OFFPAGE TRUE
J 0
(4525 -1525);
DISPLAY 0.872340 (4525 -1525);
PAINT GREEN (4525 -1525);
DISPLAY INVISIBLE (4525 -1525);
FORCEPROP 1 LAST COMMENT_BODY TRUE
J 0
(4155 -1495);
DISPLAY 0.872340 (4155 -1495);
PAINT PEACH (4155 -1495);
DISPLAY INVISIBLE (4155 -1495);
FORCEPROP 2 LAST PATH I76
J 0
(4400 -1350);
DISPLAY 1.021277 (4400 -1350);
DISPLAY INVISIBLE (4400 -1350);
FORCEADD OFFPAGE..2
(4200 -1600);
FORCEPROP 2 LAST $XR0 202 
J 0
(4389 -1600);
DISPLAY 0.638298 (4389 -1600);
PAINT MONO (4389 -1600);
FORCEPROP 2 LAST CDS_LIB standard
J 0
(4200 -1600);
PAINT MONO (4200 -1600);
DISPLAY INVISIBLE (4200 -1600);
FORCEPROP 1 LAST OFFPAGE TRUE
J 0
(4525 -1725);
DISPLAY 0.872340 (4525 -1725);
PAINT GREEN (4525 -1725);
DISPLAY INVISIBLE (4525 -1725);
FORCEPROP 1 LAST COMMENT_BODY TRUE
J 0
(4155 -1695);
DISPLAY 0.872340 (4155 -1695);
PAINT PEACH (4155 -1695);
DISPLAY INVISIBLE (4155 -1695);
FORCEPROP 2 LAST PATH I77
J 0
(4400 -1550);
DISPLAY 1.021277 (4400 -1550);
DISPLAY INVISIBLE (4400 -1550);
FORCEADD OFFPAGE..2
(4175 -1800);
FORCEPROP 2 LAST $XR1 252 
J 0
(4484 -1800);
DISPLAY 0.638298 (4484 -1800);
PAINT MONO (4484 -1800);
FORCEPROP 2 LAST $XR0 224 
J 0
(4364 -1800);
DISPLAY 0.638298 (4364 -1800);
PAINT MONO (4364 -1800);
FORCEPROP 1 LAST COMMENT_BODY TRUE
J 0
(4130 -1895);
DISPLAY 0.872340 (4130 -1895);
PAINT PEACH (4130 -1895);
DISPLAY INVISIBLE (4130 -1895);
FORCEPROP 1 LAST OFFPAGE TRUE
J 0
(4500 -1925);
DISPLAY 0.872340 (4500 -1925);
PAINT GREEN (4500 -1925);
DISPLAY INVISIBLE (4500 -1925);
FORCEPROP 2 LAST CDS_LIB standard
J 0
(4175 -1800);
PAINT MONO (4175 -1800);
DISPLAY INVISIBLE (4175 -1800);
FORCEPROP 2 LAST PATH I78
J 0
(4500 -1750);
DISPLAY 1.021277 (4500 -1750);
DISPLAY INVISIBLE (4500 -1750);
FORCEADD OFFPAGE..2
(4175 -1975);
FORCEPROP 2 LAST $XR1 240 
J 0
(4484 -1975);
DISPLAY 0.638298 (4484 -1975);
PAINT MONO (4484 -1975);
FORCEPROP 2 LAST $XR0 228 
J 0
(4364 -1975);
DISPLAY 0.638298 (4364 -1975);
PAINT MONO (4364 -1975);
FORCEPROP 2 LAST CDS_LIB standard
J 0
(4175 -1975);
DISPLAY INVISIBLE (4175 -1975);
FORCEPROP 1 LAST OFFPAGE TRUE
J 0
(4500 -2100);
DISPLAY 0.872340 (4500 -2100);
PAINT GREEN (4500 -2100);
DISPLAY INVISIBLE (4500 -2100);
FORCEPROP 1 LAST COMMENT_BODY TRUE
J 0
(4130 -2070);
DISPLAY 0.872340 (4130 -2070);
PAINT PEACH (4130 -2070);
DISPLAY INVISIBLE (4130 -2070);
FORCEPROP 2 LAST PATH I79
J 0
(4500 -1925);
DISPLAY 1.021277 (4500 -1925);
DISPLAY INVISIBLE (4500 -1925);
FORCEADD OFFPAGE..1
R 2
(2400 1425);
FORCEPROP 2 LAST $XR0 222 
J 0
(2586 1425);
DISPLAY 0.638298 (2586 1425);
PAINT MONO (2586 1425);
FORCEPROP 2 LAST PATH I8
J 0
(2600 1475);
DISPLAY 1.021277 (2600 1475);
DISPLAY INVISIBLE (2600 1475);
FORCEPROP 1 LAST OFFPAGE TRUE
J 2
(2075 1300);
DISPLAY 1.170213 (2075 1300);
PAINT GREEN (2075 1300);
DISPLAY INVISIBLE (2075 1300);
FORCEPROP 1 LAST COMMENT_BODY TRUE
J 2
(2275 1325);
DISPLAY 1.170213 (2275 1325);
PAINT GREEN (2275 1325);
DISPLAY INVISIBLE (2275 1325);
FORCEPROP 2 LAST CDS_LIB standard
J 0
(2400 1425);
DISPLAY INVISIBLE (2400 1425);
FORCEADD Q_RES..1
(2675 -1400);
FORCEPROP 1 LAST PART_NUMBER CS00002JB13
J 0
(2625 -1350);
DISPLAY 0.404255 (2625 -1350);
DISPLAY INVISIBLE (2625 -1350);
FORCEPROP 1 LAST MATERIAL CHIP
J 0
(2925 -1400);
DISPLAY 0.510638 (2925 -1400);
FORCEPROP 1 LAST TOLERANCE 5%
J 0
(2850 -1400);
DISPLAY 0.510638 (2850 -1400);
FORCEPROP 1 LAST VALUE 0
J 2
(2825 -1400);
DISPLAY 0.510638 (2825 -1400);
FORCEPROP 1 LAST $LOCATION R2412
J 0
(2475 -1400);
DISPLAY 0.638298 (2475 -1400);
FORCEPROP 1 LASTPIN (2575 -1400) $PN 1
J 0
(2587 -1388);
DISPLAY 0.787234 (2587 -1388);
PAINT MONO (2587 -1388);
FORCEPROP 1 LASTPIN (2775 -1400) $PN 2
J 0
(2737 -1388);
DISPLAY 0.787234 (2737 -1388);
PAINT MONO (2737 -1388);
FORCEPROP 1 LAST WATTAGE 1/16W
J 2
(2850 -1325);
DISPLAY 0.404255 (2850 -1325);
DISPLAY INVISIBLE (2850 -1325);
FORCEPROP 1 LAST PACK_TYPE 0402LF
J 0
(2925 -1400);
DISPLAY 0.510638 (2925 -1400);
DISPLAY INVISIBLE (2925 -1400);
FORCEPROP 2 LAST CDS_LIB pure_quanta
J 0
(2675 -1400);
DISPLAY INVISIBLE (2675 -1400);
FORCEPROP 1 LAST PATH I83
J 0
(2625 -1250);
DISPLAY 0.978723 (2625 -1250);
PAINT WHITE (2625 -1250);
DISPLAY INVISIBLE (2625 -1250);
FORCEPROP 0 LAST CDS_LOCATION R2412
J 0
(2475 -1350);
DISPLAY 1.021277 (2475 -1350);
DISPLAY INVISIBLE (2475 -1350);
FORCEPROP 0 LAST $SEC 1
J 0
(2475 -1350);
DISPLAY 0.680851 (2475 -1350);
PAINT MONO (2475 -1350);
DISPLAY INVISIBLE (2475 -1350);
FORCEPROP 0 LAST CDS_SEC 1
J 0
(2475 -1350);
DISPLAY 1.021277 (2475 -1350);
DISPLAY INVISIBLE (2475 -1350);
FORCEADD Q_RES..1
(2675 -1600);
FORCEPROP 1 LAST PART_NUMBER CS00002JB13
J 0
(2625 -1550);
DISPLAY 0.404255 (2625 -1550);
DISPLAY INVISIBLE (2625 -1550);
FORCEPROP 1 LAST TOLERANCE 5%
J 0
(2850 -1600);
DISPLAY 0.510638 (2850 -1600);
FORCEPROP 1 LAST MATERIAL CHIP
J 0
(2925 -1600);
DISPLAY 0.510638 (2925 -1600);
FORCEPROP 1 LAST VALUE 0
J 2
(2825 -1600);
DISPLAY 0.510638 (2825 -1600);
FORCEPROP 1 LAST $LOCATION R2452
J 0
(2475 -1600);
DISPLAY 0.638298 (2475 -1600);
FORCEPROP 1 LASTPIN (2575 -1600) $PN 1
J 0
(2587 -1588);
DISPLAY 0.787234 (2587 -1588);
PAINT MONO (2587 -1588);
FORCEPROP 1 LASTPIN (2775 -1600) $PN 2
J 0
(2737 -1588);
DISPLAY 0.787234 (2737 -1588);
PAINT MONO (2737 -1588);
FORCEPROP 1 LAST WATTAGE 1/16W
J 2
(2850 -1525);
DISPLAY 0.404255 (2850 -1525);
DISPLAY INVISIBLE (2850 -1525);
FORCEPROP 1 LAST PACK_TYPE 0402LF
J 0
(2925 -1600);
DISPLAY 0.510638 (2925 -1600);
DISPLAY INVISIBLE (2925 -1600);
FORCEPROP 2 LAST CDS_LIB pure_quanta
J 0
(2675 -1600);
DISPLAY INVISIBLE (2675 -1600);
FORCEPROP 1 LAST PATH I84
J 0
(2625 -1450);
DISPLAY 0.978723 (2625 -1450);
PAINT WHITE (2625 -1450);
DISPLAY INVISIBLE (2625 -1450);
FORCEPROP 0 LAST CDS_LOCATION R2452
J 0
(2475 -1550);
DISPLAY 1.021277 (2475 -1550);
DISPLAY INVISIBLE (2475 -1550);
FORCEPROP 0 LAST $SEC 1
J 0
(2475 -1550);
DISPLAY 0.680851 (2475 -1550);
PAINT MONO (2475 -1550);
DISPLAY INVISIBLE (2475 -1550);
FORCEPROP 0 LAST CDS_SEC 1
J 0
(2475 -1550);
DISPLAY 1.021277 (2475 -1550);
DISPLAY INVISIBLE (2475 -1550);
FORCEADD Q_RES..1
(2650 -1800);
FORCEPROP 1 LAST PART_NUMBER CS00002JB13
J 0
(2600 -1750);
DISPLAY 0.404255 (2600 -1750);
DISPLAY INVISIBLE (2600 -1750);
FORCEPROP 1 LAST MATERIAL CHIP
J 0
(2900 -1800);
DISPLAY 0.510638 (2900 -1800);
FORCEPROP 1 LAST TOLERANCE 5%
J 0
(2825 -1800);
DISPLAY 0.510638 (2825 -1800);
FORCEPROP 1 LAST VALUE 0
J 2
(2800 -1800);
DISPLAY 0.510638 (2800 -1800);
FORCEPROP 1 LAST $LOCATION R3047
J 0
(2450 -1800);
DISPLAY 0.510638 (2450 -1800);
FORCEPROP 1 LASTPIN (2550 -1800) $PN 1
J 0
(2562 -1788);
DISPLAY 0.787234 (2562 -1788);
PAINT MONO (2562 -1788);
FORCEPROP 1 LASTPIN (2750 -1800) $PN 2
J 0
(2712 -1788);
DISPLAY 0.787234 (2712 -1788);
PAINT MONO (2712 -1788);
FORCEPROP 1 LAST WATTAGE 1/16W
J 2
(2825 -1725);
DISPLAY 0.404255 (2825 -1725);
DISPLAY INVISIBLE (2825 -1725);
FORCEPROP 1 LAST PACK_TYPE 0402LF
J 0
(2900 -1800);
DISPLAY 0.510638 (2900 -1800);
DISPLAY INVISIBLE (2900 -1800);
FORCEPROP 2 LAST CDS_LIB pure_quanta
J 0
(2650 -1800);
DISPLAY INVISIBLE (2650 -1800);
FORCEPROP 1 LAST PATH I85
J 0
(2600 -1650);
DISPLAY 0.978723 (2600 -1650);
PAINT WHITE (2600 -1650);
DISPLAY INVISIBLE (2600 -1650);
FORCEPROP 0 LAST CDS_LOCATION R3047
J 0
(2450 -1750);
DISPLAY 1.021277 (2450 -1750);
DISPLAY INVISIBLE (2450 -1750);
FORCEPROP 0 LAST $SEC 1
J 0
(2450 -1750);
DISPLAY 0.680851 (2450 -1750);
PAINT MONO (2450 -1750);
DISPLAY INVISIBLE (2450 -1750);
FORCEPROP 0 LAST CDS_SEC 1
J 0
(2450 -1750);
DISPLAY 1.021277 (2450 -1750);
DISPLAY INVISIBLE (2450 -1750);
FORCEADD Q_RES..1
(2650 -1975);
FORCEPROP 1 LAST PART_NUMBER CS00002JB13
J 0
(2600 -1925);
DISPLAY 0.404255 (2600 -1925);
DISPLAY INVISIBLE (2600 -1925);
FORCEPROP 1 LAST VALUE 0
J 2
(2800 -1975);
DISPLAY 0.510638 (2800 -1975);
FORCEPROP 1 LAST TOLERANCE 5%
J 0
(2825 -1975);
DISPLAY 0.510638 (2825 -1975);
FORCEPROP 1 LAST MATERIAL CHIP
J 0
(2900 -1975);
DISPLAY 0.510638 (2900 -1975);
FORCEPROP 1 LAST $LOCATION R3048
J 0
(2450 -1975);
DISPLAY 0.510638 (2450 -1975);
FORCEPROP 1 LASTPIN (2550 -1975) $PN 1
J 0
(2562 -1963);
DISPLAY 0.787234 (2562 -1963);
PAINT MONO (2562 -1963);
FORCEPROP 1 LASTPIN (2750 -1975) $PN 2
J 0
(2712 -1963);
DISPLAY 0.787234 (2712 -1963);
PAINT MONO (2712 -1963);
FORCEPROP 2 LAST CDS_LIB pure_quanta
J 0
(2650 -1975);
DISPLAY INVISIBLE (2650 -1975);
FORCEPROP 1 LAST PACK_TYPE 0402LF
J 0
(2900 -1975);
DISPLAY 0.510638 (2900 -1975);
DISPLAY INVISIBLE (2900 -1975);
FORCEPROP 1 LAST WATTAGE 1/16W
J 2
(2825 -1900);
DISPLAY 0.404255 (2825 -1900);
DISPLAY INVISIBLE (2825 -1900);
FORCEPROP 1 LAST PATH I86
J 0
(2600 -1825);
DISPLAY 0.978723 (2600 -1825);
PAINT WHITE (2600 -1825);
DISPLAY INVISIBLE (2600 -1825);
FORCEPROP 0 LAST CDS_LOCATION R3048
J 0
(2450 -1925);
DISPLAY 1.021277 (2450 -1925);
DISPLAY INVISIBLE (2450 -1925);
FORCEPROP 0 LAST $SEC 1
J 0
(2450 -1925);
DISPLAY 0.680851 (2450 -1925);
PAINT MONO (2450 -1925);
DISPLAY INVISIBLE (2450 -1925);
FORCEPROP 0 LAST CDS_SEC 1
J 0
(2450 -1925);
DISPLAY 1.021277 (2450 -1925);
DISPLAY INVISIBLE (2450 -1925);
FORCEADD OFFPAGE..3
(2400 75);
FORCEPROP 2 LAST $XR0 115 
J 0
(2614 75);
DISPLAY 0.638298 (2614 75);
PAINT MONO (2614 75);
FORCEPROP 1 LAST COMMENT_BODY TRUE
J 0
(2350 -25);
DISPLAY 0.872340 (2350 -25);
PAINT GREEN (2350 -25);
DISPLAY INVISIBLE (2350 -25);
FORCEPROP 1 LAST OFFPAGE TRUE
J 0
(2725 -50);
DISPLAY 0.872340 (2725 -50);
DISPLAY INVISIBLE (2725 -50);
FORCEPROP 2 LAST CDS_LIB standard
J 0
(2400 75);
DISPLAY INVISIBLE (2400 75);
FORCEPROP 2 LAST PATH I87
J 0
(2625 125);
DISPLAY 1.021277 (2625 125);
DISPLAY INVISIBLE (2625 125);
FORCEADD OFFPAGE..3
(2400 25);
FORCEPROP 2 LAST $XR0 115 
J 0
(2614 25);
DISPLAY 0.638298 (2614 25);
PAINT MONO (2614 25);
FORCEPROP 1 LAST COMMENT_BODY TRUE
J 0
(2350 -75);
DISPLAY 0.872340 (2350 -75);
PAINT GREEN (2350 -75);
DISPLAY INVISIBLE (2350 -75);
FORCEPROP 1 LAST OFFPAGE TRUE
J 0
(2725 -100);
DISPLAY 0.872340 (2725 -100);
DISPLAY INVISIBLE (2725 -100);
FORCEPROP 2 LAST CDS_LIB standard
J 0
(2400 25);
DISPLAY INVISIBLE (2400 25);
FORCEPROP 2 LAST PATH I88
J 0
(2625 75);
DISPLAY 1.021277 (2625 75);
DISPLAY INVISIBLE (2625 75);
FORCEADD OFFPAGE..1
R 2
(2400 1375);
FORCEPROP 2 LAST $XR1 119 
J 0
(2676 1375);
DISPLAY 0.638298 (2676 1375);
PAINT MONO (2676 1375);
FORCEPROP 2 LAST $XR0 13 
J 0
(2586 1375);
DISPLAY 0.638298 (2586 1375);
PAINT MONO (2586 1375);
FORCEPROP 2 LAST PATH I9
J 0
(2700 1425);
DISPLAY 1.021277 (2700 1425);
DISPLAY INVISIBLE (2700 1425);
FORCEPROP 2 LAST CDS_LIB standard
J 0
(2400 1375);
DISPLAY INVISIBLE (2400 1375);
FORCEPROP 1 LAST COMMENT_BODY TRUE
J 2
(2275 1275);
DISPLAY 1.170213 (2275 1275);
PAINT GREEN (2275 1275);
DISPLAY INVISIBLE (2275 1275);
FORCEPROP 1 LAST OFFPAGE TRUE
J 2
(2075 1250);
DISPLAY 1.170213 (2075 1250);
PAINT GREEN (2075 1250);
DISPLAY INVISIBLE (2075 1250);
FORCEADD OFFPAGE..1
(1400 -1400);
FORCEPROP 2 LAST $XR3 182 
J 0
(758 -1400);
DISPLAY 0.638298 (758 -1400);
PAINT MONO (758 -1400);
FORCEPROP 2 LAST $XR2 307 
J 0
(878 -1400);
DISPLAY 0.638298 (878 -1400);
PAINT MONO (878 -1400);
FORCEPROP 2 LAST $XR1 306 
J 0
(998 -1400);
DISPLAY 0.638298 (998 -1400);
PAINT MONO (998 -1400);
FORCEPROP 2 LAST $XR0 244 
J 0
(1118 -1400);
DISPLAY 0.638298 (1118 -1400);
PAINT MONO (1118 -1400);
FORCEPROP 2 LAST CDS_LIB standard
J 0
(1400 -1400);
DISPLAY INVISIBLE (1400 -1400);
FORCEPROP 1 LAST COMMENT_BODY TRUE
J 0
(1525 -1500);
DISPLAY 1.170213 (1525 -1500);
PAINT GREEN (1525 -1500);
DISPLAY INVISIBLE (1525 -1500);
FORCEPROP 1 LAST OFFPAGE TRUE
J 0
(1725 -1525);
DISPLAY 0.872340 (1725 -1525);
DISPLAY INVISIBLE (1725 -1525);
FORCEPROP 2 LAST PATH I99
J 0
(1125 -1350);
DISPLAY 1.021277 (1125 -1350);
DISPLAY INVISIBLE (1125 -1350);
FORCEADD DNS..2
(2700 -2825);
PAINT RED (2700 -2825);
FORCEPROP 2 LAST CDS_LIB mstr_misc
J 0
(2700 -2825);
DISPLAY INVISIBLE (2700 -2825);
FORCEPROP 1 LAST COMMENT_BODY TRUE
R 1
J 0
(2775 -3050);
DISPLAY 0.872340 (2775 -3050);
PAINT GREEN (2775 -3050);
DISPLAY INVISIBLE (2775 -3050);
FORCEADD CAD_NOTE..1
(-1575 -3175);
FORCEPROP 0 LAST S2 LENGHT MATCH MAIN AND DEBUG PLD CLOCKS +/- 25 MILS
J 0
(-1725 -3425);
DISPLAY 1.021277 (-1725 -3425);
PAINT WHITE (-1725 -3425);
FORCEPROP 0 LAST S1 PLACE ALL RS RESISTORS WITHIN 0.5 INCHES FROM OSC.CLK PIN
J 0
(-1725 -3325);
DISPLAY 1.021277 (-1725 -3325);
PAINT WHITE (-1725 -3325);
FORCEPROP 1 LAST COMMENT_BODY TRUE
J 0
(-1550 -3075);
DISPLAY 0.978723 (-1550 -3075);
DISPLAY INVISIBLE (-1550 -3075);
FORCEPROP 2 LAST CDS_LIB logical_power
J 0
(-1575 -3175);
PAINT MONO (-1575 -3175);
DISPLAY INVISIBLE (-1575 -3175);
FORCEADD QUANTA_TITLE_BLOCK_C..1
(4925 -4100);
FORCEPROP 0 LAST CDS_CON_LAST_MODIFIED Fri Aug 25 14:03:31 2023
J 0
(3040 -4085);
PAINT MONO (3040 -4085);
DISPLAY INVISIBLE (3040 -4085);
FORCEPROP 2 LAST CUSTOM_TXT_CDS <XR_PAGE_TITLE>
J 0
(-2965 1150);
DISPLAY 0.638298 (-2965 1150);
PAINT PINK (-2965 1150);
DISPLAY INVISIBLE (-2965 1150);
FORCEPROP 2 LAST CUSTOM_TXT_CDS <CON_LAST_MODIFIED>
J 0
(3040 -4085);
DISPLAY 0.978723 (3040 -4085);
FORCEPROP 2 LAST CUSTOM_TXT_CDS <NAME_1>
J 0
(1750 -3925);
FORCEPROP 2 LAST CUSTOM_TXT_CDS <NAME_2>
J 0
(1750 -4050);
FORCEPROP 2 LAST CUSTOM_TXT_CDS <CON_PAGE_NUM> OF <CON_TOTAL_PAGES>
J 0
(4479 -4082);
DISPLAY 0.978723 (4479 -4082);
FORCEPROP 2 LAST CUSTOM_TXT_CDS <Q_NUMBER>
J 0
(3522 -3997);
DISPLAY 1.212766 (3522 -3997);
FORCEPROP 2 LAST CUSTOM_TXT_CDS <Q_PROJ>
J 0
(2543 -3998);
DISPLAY 1.212766 (2543 -3998);
FORCEPROP 2 LAST CUSTOM_TXT_CDS <Q_REV>
J 0
(4741 -3997);
DISPLAY 1.212766 (4741 -3997);
FORCEPROP 1 LAST Q_TITLE MAIN FPGA / PFR (2/5)
J 0
(-4416 -4074);
DISPLAY 1.957447 (-4416 -4074);
PAINT GREEN (-4416 -4074);
FORCEPROP 1 LAST Q_DEPT 
J 1
(1162 -4051);
DISPLAY 1.957447 (1162 -4051);
PAINT GREEN (1162 -4051);
FORCEPROP 2 LAST CDS_XR_PAGE_TITLE CR-214 : @S9S_MB_2U_LIB.S9S_MB_2U(SCH_1):PAGE214
J 0
(-2965 1150);
DISPLAY 0.638298 (-2965 1150);
PAINT PINK (-2965 1150);
DISPLAY INVISIBLE (-2965 1150);
FORCEPROP 2 LAST CDS_LIB pure_quanta
J 0
(4925 -4100);
PAINT MONO (4925 -4100);
DISPLAY INVISIBLE (4925 -4100);
FORCEPROP 1 LAST CDS_LMAN_SYM_OUTLINE -9475,6775,100,-125
J 0
(4925 -4100);
DISPLAY 0.468085 (4925 -4100);
PAINT GREEN (4925 -4100);
DISPLAY INVISIBLE (4925 -4100);
FORCEPROP 2 LAST PAGE_BORDER TRUE
J 0
(-2965 1150);
DISPLAY 0.638298 (-2965 1150);
PAINT PINK (-2965 1150);
DISPLAY INVISIBLE (-2965 1150);
FORCEPROP 1 LAST COMMENT_BODY TRUE
J 0
(4937 -4113);
DISPLAY 0.978723 (4937 -4113);
PAINT GREEN (4937 -4113);
DISPLAY INVISIBLE (4937 -4113);
WIRE 16 -1 (-3725 -2775)(-3725 -2850);
WIRE 16 -1 (-3000 -2500)(-3000 -2575);
WIRE 16 -1 (-3000 -2875)(-3000 -2950);
WIRE 16 -1 (-2000 -3175)(-2000 -3225);
WIRE 16 -1 (-2125 -3175)(-2000 -3175);
WIRE 16 -1 (-1200 -125)(-50 -125);
FORCEPROP 0 LAST CDS_PHYS_NET_NAME PWRGD_PCH_PWROK_R
J 0
(-1175 -83);
PAINT MONO (-1175 -83);
DISPLAY INVISIBLE (-1175 -83);
FORCEPROP 0 LAST SIG_NAME NC_FPGA_PR13A
J 0
(-1110 -115);
DISPLAY 0.680851 (-1110 -115);
PAINT WHITE (-1110 -115);
WIRE 16 -1 (-1200 -175)(-50 -175);
FORCEPROP 0 LAST CDS_PHYS_NET_NAME PWRGD_PVCCINFAON_CPU1
J 0
(-1175 -133);
PAINT MONO (-1175 -133);
DISPLAY INVISIBLE (-1175 -133);
FORCEPROP 0 LAST SIG_NAME OCP_V3_2_P3V3_ADC_ALERT
J 0
(-1110 -165);
DISPLAY 0.680851 (-1110 -165);
PAINT WHITE (-1110 -165);
WIRE 16 -1 (-1200 -425)(-50 -425);
FORCEPROP 0 LAST CDS_PHYS_NET_NAME PWRGD_PVCCINFAON_CPU1
J 0
(-1175 -383);
PAINT MONO (-1175 -383);
DISPLAY INVISIBLE (-1175 -383);
FORCEPROP 0 LAST SIG_NAME FM_UARTSW_LSB_N
J 0
(-1110 -415);
DISPLAY 0.680851 (-1110 -415);
PAINT WHITE (-1110 -415);
WIRE 16 -1 (-1200 -75)(-50 -75);
FORCEPROP 0 LAST CDS_PHYS_NET_NAME PWRGD_PVCCFA_EHV_CPU1
J 0
(-1175 -33);
PAINT MONO (-1175 -33);
DISPLAY INVISIBLE (-1175 -33);
FORCEPROP 0 LAST SIG_NAME OCP_SFF_P3V3_ADC_ALERT
J 0
(-1110 -65);
DISPLAY 0.680851 (-1110 -65);
PAINT WHITE (-1110 -65);
WIRE 16 -1 (-1200 -275)(-50 -275);
FORCEPROP 0 LAST CDS_PHYS_NET_NAME PWRGD_PVCCD_HV_CPU1
J 0
(-1175 -233);
PAINT MONO (-1175 -233);
DISPLAY INVISIBLE (-1175 -233);
FORCEPROP 0 LAST SIG_NAME P12V_SCM_ADC_ALERT
J 0
(-1110 -265);
DISPLAY 0.680851 (-1110 -265);
PAINT WHITE (-1110 -265);
WIRE 16 -1 (-1200 75)(-50 75);
FORCEPROP 0 LAST CDS_PHYS_NET_NAME PWRGD_SYS_PWROK_R
J 0
(-1175 117);
PAINT MONO (-1175 117);
DISPLAY INVISIBLE (-1175 117);
FORCEPROP 0 LAST SIG_NAME IRQ_PVCCFA_CPU0_VRHOT_R_N
J 0
(-1110 85);
DISPLAY 0.680851 (-1110 85);
PAINT WHITE (-1110 85);
WIRE 16 -1 (-1200 125)(-50 125);
FORCEPROP 0 LAST CDS_PHYS_NET_NAME PWRGD_PCH_PWROK_R
J 0
(-1175 167);
PAINT MONO (-1175 167);
DISPLAY INVISIBLE (-1175 167);
FORCEPROP 0 LAST SIG_NAME PWRGD_PCH_PWROK_R
J 0
(-1110 135);
DISPLAY 0.680851 (-1110 135);
PAINT WHITE (-1110 135);
WIRE 16 -1 (-1200 25)(-50 25);
FORCEPROP 0 LAST CDS_PHYS_NET_NAME PWRGD_PCH_PWROK_R
J 0
(-1175 67);
PAINT MONO (-1175 67);
DISPLAY INVISIBLE (-1175 67);
FORCEPROP 0 LAST SIG_NAME IRQ_PVCCFA_CPU1_VRHOT_R_N
J 0
(-1110 35);
DISPLAY 0.680851 (-1110 35);
PAINT WHITE (-1110 35);
WIRE 16 -1 (-1200 175)(-50 175);
FORCEPROP 0 LAST CDS_PHYS_NET_NAME PWRGD_SYS_PWROK_R
J 0
(-1175 217);
PAINT MONO (-1175 217);
DISPLAY INVISIBLE (-1175 217);
FORCEPROP 0 LAST SIG_NAME PWRGD_SYS_PWROK_R
J 0
(-1110 185);
DISPLAY 0.680851 (-1110 185);
PAINT WHITE (-1110 185);
WIRE 16 -1 (-1200 225)(-50 225);
FORCEPROP 0 LAST CDS_PHYS_NET_NAME PWRGD_P1V8_PCH_AUX_PLD
J 0
(-1175 267);
PAINT MONO (-1175 267);
DISPLAY INVISIBLE (-1175 267);
FORCEPROP 0 LAST SIG_NAME PWRGD_P1V8_PCH_AUX_PLD
J 0
(-1110 235);
DISPLAY 0.680851 (-1110 235);
PAINT WHITE (-1110 235);
WIRE 16 -1 (-1200 275)(-50 275);
FORCEPROP 0 LAST CDS_PHYS_NET_NAME PWRGD_P1V05_PCH_AUX
J 0
(-1175 317);
PAINT MONO (-1175 317);
DISPLAY INVISIBLE (-1175 317);
FORCEPROP 0 LAST SIG_NAME PWRGD_P1V05_PCH_AUX
J 0
(-1110 285);
DISPLAY 0.680851 (-1110 285);
PAINT WHITE (-1110 285);
WIRE 16 -1 (-1200 325)(-50 325);
FORCEPROP 0 LAST CDS_PHYS_NET_NAME PWRGD_PS_PWROK_PLD_R
J 0
(-1175 367);
PAINT MONO (-1175 367);
DISPLAY INVISIBLE (-1175 367);
FORCEPROP 0 LAST SIG_NAME PWRGD_PS_PWROK_PLD_ISO_R
J 0
(-1110 335);
DISPLAY 0.680851 (-1110 335);
PAINT RED (-1110 335);
WIRE 16 -1 (-1200 375)(-50 375);
FORCEPROP 0 LAST CDS_PHYS_NET_NAME FM_PFR_DSW_PWROK_N
J 0
(-1175 417);
PAINT MONO (-1175 417);
DISPLAY INVISIBLE (-1175 417);
FORCEPROP 0 LAST SIG_NAME FM_PFR_DSW_PWROK_N
J 0
(-1110 385);
DISPLAY 0.680851 (-1110 385);
PAINT WHITE (-1110 385);
WIRE 16 -1 (-1200 425)(-50 425);
FORCEPROP 0 LAST CDS_PHYS_NET_NAME PWRGD_PVCCD_HV_CPU1
J 0
(-1175 467);
PAINT MONO (-1175 467);
DISPLAY INVISIBLE (-1175 467);
FORCEPROP 0 LAST SIG_NAME PWRGD_PVCCD_HV_CPU1
J 0
(-1110 435);
DISPLAY 0.680851 (-1110 435);
PAINT WHITE (-1110 435);
WIRE 16 -1 (-1200 475)(-50 475);
FORCEPROP 0 LAST CDS_PHYS_NET_NAME PWRGD_PVCCFA_EHV_FIVRA_CPU1
J 0
(-1175 517);
PAINT MONO (-1175 517);
DISPLAY INVISIBLE (-1175 517);
FORCEPROP 0 LAST SIG_NAME PWRGD_PVCCFA_EHV_FIVRA_CPU1
J 0
(-1110 485);
DISPLAY 0.680851 (-1110 485);
PAINT WHITE (-1110 485);
WIRE 16 -1 (-1200 525)(-50 525);
FORCEPROP 0 LAST CDS_PHYS_NET_NAME PWRGD_PVCCINFAON_CPU1
J 0
(-1175 567);
PAINT MONO (-1175 567);
DISPLAY INVISIBLE (-1175 567);
FORCEPROP 0 LAST SIG_NAME PWRGD_PVCCINFAON_CPU1
J 0
(-1110 535);
DISPLAY 0.680851 (-1110 535);
PAINT WHITE (-1110 535);
WIRE 16 -1 (-1200 575)(-50 575);
FORCEPROP 0 LAST CDS_PHYS_NET_NAME PWRGD_PVCCINFAON_CPU0
J 0
(-1175 617);
PAINT MONO (-1175 617);
DISPLAY INVISIBLE (-1175 617);
FORCEPROP 0 LAST SIG_NAME PWRGD_PVCCINFAON_CPU0
J 0
(-1110 585);
DISPLAY 0.680851 (-1110 585);
PAINT WHITE (-1110 585);
WIRE 16 -1 (-1200 625)(-50 625);
FORCEPROP 0 LAST CDS_PHYS_NET_NAME PWRGD_PVCCFA_EHV_CPU1
J 0
(-1175 667);
PAINT MONO (-1175 667);
DISPLAY INVISIBLE (-1175 667);
FORCEPROP 0 LAST SIG_NAME PWRGD_PVCCFA_EHV_CPU1
J 0
(-1110 635);
DISPLAY 0.680851 (-1110 635);
PAINT WHITE (-1110 635);
WIRE 16 -1 (-1200 -25)(-50 -25);
FORCEPROP 0 LAST CDS_PHYS_NET_NAME PWRGD_PVCCFA_EHV_CPU0
J 0
(-1175 17);
PAINT MONO (-1175 17);
DISPLAY INVISIBLE (-1175 17);
FORCEPROP 0 LAST SIG_NAME E1S_0_P3V3_ADC_ALERT
J 0
(-1110 -15);
DISPLAY 0.680851 (-1110 -15);
PAINT WHITE (-1110 -15);
WIRE 16 -1 (2350 -325)(1200 -325);
FORCEPROP 2 LAST SIG_NAME E1S_0_LED_ACT_R_N
J 0
(1340 -315);
DISPLAY 0.553191 (1340 -315);
PAINT WHITE (1340 -315);
WIRE 16 -1 (2350 -275)(1200 -275);
FORCEPROP 0 LAST CDS_PHYS_NET_NAME FM_SMB_2_ALERT_GPU_ISO_R_N
J 0
(2165 -233);
PAINT MONO (2165 -233);
DISPLAY INVISIBLE (2165 -233);
FORCEPROP 2 LAST SIG_NAME FM_SMB_2_ALERT_GPU_ISO_R_N
J 0
(1340 -265);
DISPLAY 0.553191 (1340 -265);
PAINT WHITE (1340 -265);
FORCEPROP 0 LAST $PHYS_NET_NAME RST_PCIE_M2_N
J 0
(2165 -186);
PAINT MONO (2165 -186);
DISPLAY INVISIBLE (2165 -186);
WIRE 16 -1 (2350 -225)(1200 -225);
FORCEPROP 0 LAST CDS_PHYS_NET_NAME FM_SMB_1_ALERT_GPU_ISO_R_N
J 0
(1915 -183);
PAINT MONO (1915 -183);
DISPLAY INVISIBLE (1915 -183);
FORCEPROP 2 LAST SIG_NAME FM_SMB_1_ALERT_GPU_ISO_R_N
J 0
(1340 -215);
DISPLAY 0.553191 (1340 -215);
PAINT WHITE (1340 -215);
FORCEPROP 0 LAST $PHYS_NET_NAME RST_PCIE_M2_N
J 0
(1915 -136);
PAINT MONO (1915 -136);
DISPLAY INVISIBLE (1915 -136);
WIRE 16 -1 (2350 -175)(1200 -175);
FORCEPROP 2 LAST SIG_NAME HP_LVC3_OCP_V3_1_HSC_PWRGD_PLD_R
J 0
(1340 -165);
DISPLAY 0.553191 (1340 -165);
PAINT WHITE (1340 -165);
WIRE 16 -1 (2350 -125)(1200 -125);
FORCEPROP 2 LAST SIG_NAME HP_LVC3_OCP_V3_2_HSC_PWRGD_PLD_R
J 0
(1340 -115);
DISPLAY 0.553191 (1340 -115);
PAINT WHITE (1340 -115);
WIRE 16 -1 (2350 -75)(1200 -75);
FORCEPROP 2 LAST SIG_NAME OCP_V3_2_MAIN_PWR_EN
J 0
(1340 -65);
DISPLAY 0.553191 (1340 -65);
PAINT WHITE (1340 -65);
WIRE 16 -1 (2350 -25)(1200 -25);
FORCEPROP 2 LAST SIG_NAME OCP_SFF_MAIN_PWR_EN
J 0
(1340 -15);
DISPLAY 0.553191 (1340 -15);
PAINT WHITE (1340 -15);
WIRE 16 -1 (1200 25)(2350 25);
FORCEPROP 0 LAST CDS_PHYS_NET_NAME PWRGD_FAIL_CPU1_AB_R
J 0
(1225 67);
PAINT MONO (1225 67);
DISPLAY INVISIBLE (1225 67);
FORCEPROP 0 LAST SIG_NAME PWRGD_FAIL_CPU1_GH_R
J 0
(1340 35);
DISPLAY 0.680851 (1340 35);
PAINT WHITE (1340 35);
WIRE 16 -1 (1200 75)(2350 75);
FORCEPROP 0 LAST CDS_PHYS_NET_NAME PWRGD_FAIL_CPU1_EF_R
J 0
(1225 117);
PAINT MONO (1225 117);
DISPLAY INVISIBLE (1225 117);
FORCEPROP 0 LAST SIG_NAME PWRGD_FAIL_CPU1_EF_R
J 0
(1340 85);
DISPLAY 0.680851 (1340 85);
PAINT WHITE (1340 85);
WIRE 16 -1 (1200 125)(2350 125);
FORCEPROP 0 LAST CDS_PHYS_NET_NAME PWRGD_FAIL_CPU1_CD_R
J 0
(1225 167);
PAINT MONO (1225 167);
DISPLAY INVISIBLE (1225 167);
FORCEPROP 0 LAST SIG_NAME PWRGD_FAIL_CPU1_CD_R
J 0
(1340 135);
DISPLAY 0.680851 (1340 135);
PAINT WHITE (1340 135);
WIRE 16 -1 (1200 175)(2350 175);
FORCEPROP 0 LAST CDS_PHYS_NET_NAME PWRGD_FAIL_CPU1_GH_R
J 0
(1225 217);
PAINT MONO (1225 217);
DISPLAY INVISIBLE (1225 217);
FORCEPROP 0 LAST SIG_NAME PWRGD_FAIL_CPU1_AB_R
J 0
(1340 185);
DISPLAY 0.680851 (1340 185);
PAINT WHITE (1340 185);
WIRE 16 -1 (1200 225)(2350 225);
FORCEPROP 0 LAST CDS_PHYS_NET_NAME PWRGD_FAIL_CPU0_EF_R
J 0
(1225 267);
PAINT MONO (1225 267);
DISPLAY INVISIBLE (1225 267);
FORCEPROP 0 LAST SIG_NAME PWRGD_FAIL_CPU0_GH_R
J 0
(1340 235);
DISPLAY 0.680851 (1340 235);
PAINT WHITE (1340 235);
WIRE 16 -1 (1200 325)(2350 325);
FORCEPROP 0 LAST CDS_PHYS_NET_NAME PWRGD_FAIL_CPU0_AB_R
J 0
(1225 367);
PAINT MONO (1225 367);
DISPLAY INVISIBLE (1225 367);
FORCEPROP 0 LAST SIG_NAME PWRGD_FAIL_CPU0_EF_R
J 0
(1340 335);
DISPLAY 0.680851 (1340 335);
PAINT WHITE (1340 335);
WIRE 16 -1 (1200 375)(2350 375);
FORCEPROP 0 LAST CDS_PHYS_NET_NAME PWRGD_FAIL_CPU0_CD_R
J 0
(1225 417);
PAINT MONO (1225 417);
DISPLAY INVISIBLE (1225 417);
FORCEPROP 0 LAST SIG_NAME PWRGD_FAIL_CPU0_CD_R
J 0
(1340 385);
DISPLAY 0.680851 (1340 385);
PAINT WHITE (1340 385);
WIRE 16 -1 (1200 425)(2350 425);
FORCEPROP 0 LAST CDS_PHYS_NET_NAME PWRGD_FAIL_CPU0_GH_R
J 0
(1225 467);
PAINT MONO (1225 467);
DISPLAY INVISIBLE (1225 467);
FORCEPROP 0 LAST SIG_NAME PWRGD_FAIL_CPU0_AB_R
J 0
(1340 435);
DISPLAY 0.680851 (1340 435);
PAINT WHITE (1340 435);
WIRE 16 -1 (1200 475)(2350 475);
FORCEPROP 0 LAST CDS_PHYS_NET_NAME FM_PS_EN_PLD_R
J 0
(1225 517);
PAINT MONO (1225 517);
DISPLAY INVISIBLE (1225 517);
FORCEPROP 0 LAST SIG_NAME FM_PS_EN_PLD_R
J 0
(1340 485);
DISPLAY 0.680851 (1340 485);
PAINT WHITE (1340 485);
WIRE 16 -1 (1200 525)(2350 525);
FORCEPROP 0 LAST CDS_PHYS_NET_NAME FM_SLPS4_PLD_N
J 0
(1225 567);
PAINT MONO (1225 567);
DISPLAY INVISIBLE (1225 567);
FORCEPROP 0 LAST SIG_NAME FM_SLPS4_PLD_N
J 0
(1340 535);
DISPLAY 0.680851 (1340 535);
PAINT WHITE (1340 535);
WIRE 16 -1 (1200 575)(2350 575);
FORCEPROP 0 LAST CDS_PHYS_NET_NAME FM_JTAG_BMC_MUX_SEL_R
J 0
(1225 617);
PAINT MONO (1225 617);
DISPLAY INVISIBLE (1225 617);
FORCEPROP 0 LAST SIG_NAME FM_JTAG_BMC_MUX_SEL_R
J 0
(1340 585);
DISPLAY 0.680851 (1340 585);
PAINT WHITE (1340 585);
WIRE 16 -1 (1200 675)(2350 675);
FORCEPROP 0 LAST CDS_PHYS_NET_NAME FM_RST_PERST_BIT1
J 0
(1225 717);
PAINT MONO (1225 717);
DISPLAY INVISIBLE (1225 717);
FORCEPROP 0 LAST SIG_NAME FM_RST_PERST_BIT1
J 0
(1340 685);
DISPLAY 0.680851 (1340 685);
PAINT WHITE (1340 685);
WIRE 16 -1 (1200 725)(2350 725);
FORCEPROP 0 LAST CDS_PHYS_NET_NAME FM_RST_PERST_BIT0
J 0
(1225 767);
PAINT MONO (1225 767);
DISPLAY INVISIBLE (1225 767);
FORCEPROP 0 LAST SIG_NAME FM_RST_PERST_BIT0
J 0
(1340 735);
DISPLAY 0.680851 (1340 735);
PAINT WHITE (1340 735);
WIRE 16 -1 (1200 625)(2350 625);
FORCEPROP 0 LAST CDS_PHYS_NET_NAME FM_CPU_RMCA_CATERR_DLY_LVT3_R_N
J 0
(1225 667);
PAINT MONO (1225 667);
DISPLAY INVISIBLE (1225 667);
FORCEPROP 0 LAST SIG_NAME FM_CPU_RMCA_CATERR_DLY_LVT3_R_N
J 0
(1340 635);
DISPLAY 0.680851 (1340 635);
PAINT WHITE (1340 635);
WIRE 16 -1 (-1200 -225)(-50 -225);
FORCEPROP 0 LAST CDS_PHYS_NET_NAME PWRGD_PVCCFA_EHV_FIVRA_CPU1
J 0
(-1175 -183);
PAINT MONO (-1175 -183);
DISPLAY INVISIBLE (-1175 -183);
FORCEPROP 0 LAST SIG_NAME M2_0_P3V3_ADC_ALERT
J 0
(-1110 -215);
DISPLAY 0.680851 (-1110 -215);
PAINT WHITE (-1110 -215);
WIRE 16 -1 (-1200 -325)(-50 -325);
FORCEPROP 0 LAST CDS_PHYS_NET_NAME PWRGD_PVCCFA_EHV_FIVRA_CPU1
J 0
(-1175 -283);
PAINT MONO (-1175 -283);
DISPLAY INVISIBLE (-1175 -283);
FORCEPROP 0 LAST SIG_NAME NC_FPGA_PR14A
J 0
(-1110 -315);
DISPLAY 0.680851 (-1110 -315);
PAINT WHITE (-1110 -315);
WIRE 16 -1 (-1200 -375)(-50 -375);
FORCEPROP 0 LAST CDS_PHYS_NET_NAME PWRGD_PVCCD_HV_CPU1
J 0
(-1175 -333);
PAINT MONO (-1175 -333);
DISPLAY INVISIBLE (-1175 -333);
FORCEPROP 0 LAST SIG_NAME NC_FPGA_PR14B
J 0
(-1110 -365);
DISPLAY 0.680851 (-1110 -365);
PAINT WHITE (-1110 -365);
WIRE 16 -1 (1200 775)(2350 775);
FORCEPROP 0 LAST CDS_PHYS_NET_NAME IRQ_CPU1_VRHOT_N
J 0
(1225 817);
PAINT MONO (1225 817);
DISPLAY INVISIBLE (1225 817);
FORCEPROP 0 LAST SIG_NAME IRQ_PVCCIN_CPU1_VRHOT_R_N
J 0
(1340 785);
DISPLAY 0.680851 (1340 785);
PAINT WHITE (1340 785);
WIRE 16 -1 (1200 825)(2350 825);
FORCEPROP 0 LAST CDS_PHYS_NET_NAME IRQ_CPU0_VRHOT_N
J 0
(1225 867);
PAINT MONO (1225 867);
DISPLAY INVISIBLE (1225 867);
FORCEPROP 0 LAST SIG_NAME IRQ_PVCCIN_CPU0_VRHOT_R_N
J 0
(1340 835);
DISPLAY 0.680851 (1340 835);
PAINT WHITE (1340 835);
WIRE 16 -1 (-1200 675)(-50 675);
FORCEPROP 0 LAST CDS_PHYS_NET_NAME PWRGD_PVCCFA_EHV_CPU0
J 0
(-1175 717);
PAINT MONO (-1175 717);
DISPLAY INVISIBLE (-1175 717);
FORCEPROP 0 LAST SIG_NAME PWRGD_PVCCFA_EHV_CPU0
J 0
(-1110 685);
DISPLAY 0.680851 (-1110 685);
PAINT WHITE (-1110 685);
WIRE 16 -1 (-1200 725)(-50 725);
FORCEPROP 0 LAST CDS_PHYS_NET_NAME PWRGD_PVCCIN_CPU1
J 0
(-1175 767);
PAINT MONO (-1175 767);
DISPLAY INVISIBLE (-1175 767);
FORCEPROP 0 LAST SIG_NAME PWRGD_PVCCIN_CPU1
J 0
(-1110 735);
DISPLAY 0.680851 (-1110 735);
PAINT WHITE (-1110 735);
WIRE 16 -1 (1200 875)(2350 875);
FORCEPROP 0 LAST CDS_PHYS_NET_NAME PWRGD_DSW_PWROK_R3
J 0
(1225 917);
PAINT MONO (1225 917);
DISPLAY INVISIBLE (1225 917);
FORCEPROP 0 LAST SIG_NAME PWRGD_DSW_PWROK_R3
J 0
(1340 885);
DISPLAY 0.680851 (1340 885);
PAINT WHITE (1340 885);
WIRE 16 -1 (1200 925)(2350 925);
FORCEPROP 0 LAST CDS_PHYS_NET_NAME FM_CPU1_PKGID2
J 0
(1225 967);
PAINT MONO (1225 967);
DISPLAY INVISIBLE (1225 967);
FORCEPROP 0 LAST SIG_NAME FM_CPU1_PKGID2
J 0
(1340 935);
DISPLAY 0.680851 (1340 935);
PAINT WHITE (1340 935);
WIRE 16 -1 (1200 975)(2350 975);
FORCEPROP 0 LAST CDS_PHYS_NET_NAME FM_CPU1_PKGID1
J 0
(1225 1017);
PAINT MONO (1225 1017);
DISPLAY INVISIBLE (1225 1017);
FORCEPROP 0 LAST SIG_NAME FM_CPU1_PKGID1
J 0
(1340 985);
DISPLAY 0.680851 (1340 985);
PAINT WHITE (1340 985);
WIRE 16 -1 (1200 1025)(2350 1025);
FORCEPROP 0 LAST CDS_PHYS_NET_NAME FM_CPU1_PKGID0
J 0
(1225 1067);
PAINT MONO (1225 1067);
DISPLAY INVISIBLE (1225 1067);
FORCEPROP 0 LAST SIG_NAME FM_CPU1_PKGID0
J 0
(1340 1035);
DISPLAY 0.680851 (1340 1035);
PAINT WHITE (1340 1035);
WIRE 16 -1 (-1200 -475)(-50 -475);
FORCEPROP 0 LAST CDS_PHYS_NET_NAME PWRGD_PVCCFA_EHV_FIVRA_CPU1
J 0
(-1175 -433);
PAINT MONO (-1175 -433);
DISPLAY INVISIBLE (-1175 -433);
FORCEPROP 0 LAST SIG_NAME FM_UARTSW_MSB_N
J 0
(-1110 -465);
DISPLAY 0.680851 (-1110 -465);
PAINT WHITE (-1110 -465);
WIRE 16 -1 (-1200 -525)(-50 -525);
FORCEPROP 0 LAST CDS_PHYS_NET_NAME PWRGD_PVCCD_HV_CPU1
J 0
(-1175 -483);
PAINT MONO (-1175 -483);
DISPLAY INVISIBLE (-1175 -483);
FORCEPROP 0 LAST SIG_NAME FM_SOL_UART_CH_SEL
J 0
(-1110 -515);
DISPLAY 0.680851 (-1110 -515);
PAINT WHITE (-1110 -515);
WIRE 16 -1 (-1200 -575)(-50 -575);
FORCEPROP 2 LAST SIG_NAME FM_THERMAL_ALERT_R_N
J 0
(-1110 -565);
DISPLAY 0.638298 (-1110 -565);
PAINT WHITE (-1110 -565);
WIRE 16 -1 (-1200 -625)(-50 -625);
FORCEPROP 0 LAST CDS_PHYS_NET_NAME PWRGD_SYS_PWROK_R
J 0
(-1175 -583);
PAINT MONO (-1175 -583);
DISPLAY INVISIBLE (-1175 -583);
FORCEPROP 0 LAST SIG_NAME NC_FPGA_PR16C
J 0
(-1110 -615);
DISPLAY 0.680851 (-1110 -615);
PAINT WHITE (-1110 -615);
WIRE 16 -1 (-1200 -675)(-50 -675);
FORCEPROP 0 LAST CDS_PHYS_NET_NAME PWRGD_PCH_PWROK_R
J 0
(-1175 -633);
PAINT MONO (-1175 -633);
DISPLAY INVISIBLE (-1175 -633);
FORCEPROP 0 LAST SIG_NAME NC_FPGA_PR16D
J 0
(-1110 -665);
DISPLAY 0.680851 (-1110 -665);
PAINT WHITE (-1110 -665);
WIRE 16 2175 (850 -1200)(4500 -1200);
WIRE 16 2175 (4500 -850)(4500 -1200);
WIRE 16 2175 (850 -850)(850 -1200);
WIRE 16 2175 (850 -850)(4500 -850);
WIRE 16 -1 (1450 -1175)(2600 -1175);
FORCEPROP 0 LAST CDS_PHYS_NET_NAME IRQ_PCH_SCI_WHEA_R_N
J 0
(1475 -1133);
PAINT MONO (1475 -1133);
DISPLAY INVISIBLE (1475 -1133);
FORCEPROP 0 LAST SIG_NAME HP_LVC3_OCP_V3_1_P12V_PWRGD
J 0
(1550 -1165);
DISPLAY 0.680851 (1550 -1165);
PAINT WHITE (1550 -1165);
WIRE 16 -1 (1200 -725)(2350 -725);
FORCEPROP 0 LAST CDS_PHYS_NET_NAME NC_FPGA_PR16D
J 0
(1225 -683);
PAINT MONO (1225 -683);
DISPLAY INVISIBLE (1225 -683);
FORCEPROP 0 LAST SIG_NAME NC_FPGA_PR30D
J 0
(1340 -715);
DISPLAY 0.680851 (1340 -715);
PAINT WHITE (1340 -715);
WIRE 16 -1 (1200 -675)(2350 -675);
FORCEPROP 0 LAST CDS_PHYS_NET_NAME PWRGD_PCH_PWROK_R
J 0
(1225 -633);
PAINT MONO (1225 -633);
DISPLAY INVISIBLE (1225 -633);
FORCEPROP 0 LAST SIG_NAME RST_PERST_SWB_N
J 0
(1340 -665);
DISPLAY 0.680851 (1340 -665);
PAINT WHITE (1340 -665);
WIRE 16 -1 (2350 -625)(1200 -625);
FORCEPROP 0 LAST CDS_PHYS_NET_NAME GPU_FPGA_RST_R_N
J 0
(1940 -583);
PAINT MONO (1940 -583);
DISPLAY INVISIBLE (1940 -583);
FORCEPROP 2 LAST SIG_NAME FM_PCH_SPKR_R
J 0
(1340 -615);
DISPLAY 0.702128 (1340 -615);
PAINT WHITE (1340 -615);
WIRE 16 -1 (1200 -475)(2350 -475);
FORCEPROP 0 LAST CDS_PHYS_NET_NAME GPU_FPGA_RST_N
J 0
(1965 -441);
PAINT MONO (1965 -441);
DISPLAY INVISIBLE (1965 -441);
FORCEPROP 2 LAST SIG_NAME FM_JTAG_TCK_MUX_SEL_R
J 0
(1340 -465);
DISPLAY 0.638298 (1340 -465);
PAINT WHITE (1340 -465);
WIRE 16 -1 (1200 -575)(2350 -575);
FORCEPROP 0 LAST CDS_PHYS_NET_NAME GPU_FPGA_RST_N
J 0
(1965 -541);
PAINT MONO (1965 -541);
DISPLAY INVISIBLE (1965 -541);
FORCEPROP 2 LAST SIG_NAME FM_BMC_CPU_FBRK_OUT_R_N
J 0
(1340 -565);
DISPLAY 0.638298 (1340 -565);
PAINT WHITE (1340 -565);
WIRE 16 -1 (1200 -525)(2350 -525);
FORCEPROP 0 LAST CDS_PHYS_NET_NAME GPU_FPGA_RST_N
J 0
(1965 -491);
PAINT MONO (1965 -491);
DISPLAY INVISIBLE (1965 -491);
FORCEPROP 2 LAST SIG_NAME CLK_GEN2_GPU_FPGA_OE_R_N
J 0
(1340 -515);
DISPLAY 0.638298 (1340 -515);
PAINT WHITE (1340 -515);
WIRE 16 -1 (1200 -375)(2350 -375);
FORCEPROP 0 LAST CDS_PHYS_NET_NAME FM_SMB_1_ALERT_GPU_ISO_R_N
J 0
(1515 -335);
PAINT MONO (1515 -335);
DISPLAY INVISIBLE (1515 -335);
FORCEPROP 2 LAST SIG_NAME LED_HDD_ACTIVITY_B_PLD_N
J 0
(1340 -365);
DISPLAY 0.638298 (1340 -365);
PAINT WHITE (1340 -365);
WIRE 16 -1 (1200 -425)(2350 -425);
FORCEPROP 0 LAST CDS_PHYS_NET_NAME GPU_FPGA_RST_N
J 0
(1965 -391);
PAINT MONO (1965 -391);
DISPLAY INVISIBLE (1965 -391);
FORCEPROP 2 LAST SIG_NAME GPU_FPGA_RST_N
J 0
(1340 -415);
DISPLAY 0.638298 (1340 -415);
PAINT WHITE (1340 -415);
WIRE 16 -1 (1200 1225)(2350 1225);
FORCEPROP 0 LAST CDS_PHYS_NET_NAME FM_CPU1_PROC_ID1
J 0
(1225 1267);
PAINT MONO (1225 1267);
DISPLAY INVISIBLE (1225 1267);
FORCEPROP 0 LAST SIG_NAME FM_CPU1_PROC_ID1
J 0
(1340 1235);
DISPLAY 0.680851 (1340 1235);
PAINT WHITE (1340 1235);
WIRE 16 -1 (1200 1275)(2350 1275);
FORCEPROP 0 LAST CDS_PHYS_NET_NAME FM_CPU1_PROC_ID0
J 0
(1225 1317);
PAINT MONO (1225 1317);
DISPLAY INVISIBLE (1225 1317);
FORCEPROP 0 LAST SIG_NAME FM_CPU1_PROC_ID0
J 0
(1340 1285);
DISPLAY 0.680851 (1340 1285);
PAINT WHITE (1340 1285);
WIRE 16 -1 (1200 1325)(2350 1325);
FORCEPROP 0 LAST CDS_PHYS_NET_NAME FM_CPU0_PROC_ID1
J 0
(1225 1367);
PAINT MONO (1225 1367);
DISPLAY INVISIBLE (1225 1367);
FORCEPROP 0 LAST SIG_NAME FM_CPU0_PROC_ID1
J 0
(1340 1335);
DISPLAY 0.680851 (1340 1335);
PAINT WHITE (1340 1335);
WIRE 16 -1 (1200 1175)(2350 1175);
FORCEPROP 0 LAST CDS_PHYS_NET_NAME FM_CPU0_PKGID0
J 0
(1225 1217);
PAINT MONO (1225 1217);
DISPLAY INVISIBLE (1225 1217);
FORCEPROP 0 LAST SIG_NAME FM_CPU0_PKGID0
J 0
(1340 1185);
DISPLAY 0.680851 (1340 1185);
PAINT WHITE (1340 1185);
WIRE 16 -1 (1200 1125)(2350 1125);
FORCEPROP 0 LAST CDS_PHYS_NET_NAME FM_CPU0_PKGID1
J 0
(1225 1167);
PAINT MONO (1225 1167);
DISPLAY INVISIBLE (1225 1167);
FORCEPROP 0 LAST SIG_NAME FM_CPU0_PKGID1
J 0
(1340 1135);
DISPLAY 0.680851 (1340 1135);
PAINT WHITE (1340 1135);
WIRE 16 -1 (1200 1525)(2350 1525);
FORCEPROP 0 LAST CDS_PHYS_NET_NAME RST_PCIE_CPU1_DEV_PERST_N
J 0
(1225 1567);
PAINT MONO (1225 1567);
DISPLAY INVISIBLE (1225 1567);
FORCEPROP 0 LAST SIG_NAME RST_PCIE_CPU1_DEV_PERST_N
J 0
(1340 1535);
DISPLAY 0.680851 (1340 1535);
PAINT WHITE (1340 1535);
WIRE 16 -1 (1200 1075)(2350 1075);
FORCEPROP 0 LAST CDS_PHYS_NET_NAME FM_CPU0_PKGID2
J 0
(1225 1117);
PAINT MONO (1225 1117);
DISPLAY INVISIBLE (1225 1117);
FORCEPROP 0 LAST SIG_NAME FM_CPU0_PKGID2
J 0
(1340 1085);
DISPLAY 0.680851 (1340 1085);
PAINT WHITE (1340 1085);
WIRE 16 -1 (1200 1375)(2350 1375);
FORCEPROP 0 LAST CDS_PHYS_NET_NAME FM_CPU0_PROC_ID0
J 0
(1225 1417);
PAINT MONO (1225 1417);
DISPLAY INVISIBLE (1225 1417);
FORCEPROP 0 LAST SIG_NAME FM_CPU0_PROC_ID0
J 0
(1340 1385);
DISPLAY 0.680851 (1340 1385);
PAINT WHITE (1340 1385);
WIRE 16 -1 (1200 1425)(2350 1425);
FORCEPROP 0 LAST CDS_PHYS_NET_NAME FM_CPU1_SKTOCC_LVT3_PLD_N
J 0
(1225 1467);
PAINT MONO (1225 1467);
DISPLAY INVISIBLE (1225 1467);
FORCEPROP 0 LAST SIG_NAME FM_CPU1_SKTOCC_LVT3_PLD_N
J 0
(1340 1435);
DISPLAY 0.680851 (1340 1435);
PAINT WHITE (1340 1435);
WIRE 16 -1 (1200 1475)(2350 1475);
FORCEPROP 0 LAST CDS_PHYS_NET_NAME FM_CPU0_SKTOCC_LVT3_PLD_N
J 0
(1225 1517);
PAINT MONO (1225 1517);
DISPLAY INVISIBLE (1225 1517);
FORCEPROP 0 LAST SIG_NAME FM_CPU0_SKTOCC_LVT3_PLD_N
J 0
(1340 1485);
DISPLAY 0.680851 (1340 1485);
PAINT WHITE (1340 1485);
WIRE 16 -1 (1450 -1000)(2600 -1000);
FORCEPROP 0 LAST CDS_PHYS_NET_NAME FM_ADR_ACK_R
J 0
(1475 -958);
PAINT MONO (1475 -958);
DISPLAY INVISIBLE (1475 -958);
FORCEPROP 0 LAST SIG_NAME HP_LVC3_OCP_V3_2_P12V_PWRGD
J 0
(1550 -990);
DISPLAY 0.680851 (1550 -990);
PAINT WHITE (1550 -990);
WIRE 16 -1 (2800 -1000)(4150 -1000);
FORCEPROP 0 LAST CDS_PHYS_NET_NAME FM_ADR_ACK
J 0
(2825 -958);
PAINT MONO (2825 -958);
DISPLAY INVISIBLE (2825 -958);
FORCEPROP 0 LAST SIG_NAME HP_LVC3_OCP_V3_2_HSC_PWRGD_PLD_R
J 0
(3090 -990);
DISPLAY 0.680851 (3090 -990);
PAINT WHITE (3090 -990);
WIRE 16 -1 (1450 -1400)(2575 -1400);
FORCEPROP 0 LAST CDS_PHYS_NET_NAME PWRGD_DSW_PWROK
J 0
(1475 -1358);
PAINT MONO (1475 -1358);
DISPLAY INVISIBLE (1475 -1358);
FORCEPROP 0 LAST SIG_NAME PWRGD_DSW_PWROK
J 0
(1550 -1390);
DISPLAY 0.680851 (1550 -1390);
PAINT WHITE (1550 -1390);
WIRE 16 -1 (-1200 1625)(-50 1625);
FORCEPROP 0 LAST CDS_PHYS_NET_NAME FM_PVCCD_HV_CPU1_EN
J 0
(-1175 1667);
PAINT MONO (-1175 1667);
DISPLAY INVISIBLE (-1175 1667);
FORCEPROP 0 LAST SIG_NAME FM_PVCCD_HV_CPU1_EN
J 0
(-1110 1635);
DISPLAY 0.680851 (-1110 1635);
PAINT WHITE (-1110 1635);
WIRE 16 -1 (-1200 1375)(-50 1375);
FORCEPROP 0 LAST CDS_PHYS_NET_NAME FM_PVCCINFAON_CPU0_R_EN
J 0
(-1175 1417);
PAINT MONO (-1175 1417);
DISPLAY INVISIBLE (-1175 1417);
FORCEPROP 0 LAST SIG_NAME FM_PVCCINFAON_CPU0_R_EN
J 0
(-1110 1385);
DISPLAY 0.680851 (-1110 1385);
PAINT WHITE (-1110 1385);
WIRE 16 -1 (2775 -1400)(4150 -1400);
FORCEPROP 0 LAST CDS_PHYS_NET_NAME VOL_SEN_ALERT_R
J 0
(3090 -1360);
PAINT MONO (3090 -1360);
DISPLAY INVISIBLE (3090 -1360);
FORCEPROP 2 LAST SIG_NAME PWRGD_DSW_PWROK_R3
J 0
(3140 -1390);
DISPLAY 0.638298 (3140 -1390);
PAINT WHITE (3140 -1390);
WIRE 16 -1 (2775 -1600)(4150 -1600);
FORCEPROP 0 LAST CDS_PHYS_NET_NAME FM_ESPI_PLD_R1_EN
J 0
(3090 -1560);
PAINT MONO (3090 -1560);
DISPLAY INVISIBLE (3090 -1560);
FORCEPROP 2 LAST SIG_NAME FM_ESPI_PLD_R1_EN
J 0
(3140 -1590);
DISPLAY 0.638298 (3140 -1590);
PAINT WHITE (3140 -1590);
WIRE 16 -1 (2750 -1800)(4125 -1800);
FORCEPROP 0 LAST CDS_PHYS_NET_NAME PWRGD_PS_PWROK_PLD
J 0
(3065 -1760);
PAINT MONO (3065 -1760);
DISPLAY INVISIBLE (3065 -1760);
FORCEPROP 2 LAST SIG_NAME PWRGD_PS_PWROK_PLD
J 0
(3115 -1790);
DISPLAY 0.638298 (3115 -1790);
PAINT WHITE (3115 -1790);
WIRE 16 -1 (2750 -1975)(4125 -1975);
FORCEPROP 2 LAST SIG_NAME PWRGD_PS_PWROK
J 0
(3115 -1965);
DISPLAY 0.638298 (3115 -1965);
PAINT WHITE (3115 -1965);
WIRE 16 -1 (2300 -1975)(2550 -1975);
WIRE 16 -1 (2300 -1800)(2300 -1975);
WIRE 16 -1 (2300 -1800)(2550 -1800);
WIRE 16 -1 (1425 -1800)(2300 -1800);
FORCEPROP 0 LAST CDS_PHYS_NET_NAME MB0_P12V_STBY_PWRGD
J 0
(1450 -1758);
PAINT MONO (1450 -1758);
DISPLAY INVISIBLE (1450 -1758);
FORCEPROP 0 LAST SIG_NAME MB0_P12V_STBY_PWRGD
J 0
(1525 -1790);
DISPLAY 0.680851 (1525 -1790);
PAINT WHITE (1525 -1790);
WIRE 16 -1 (200 -2675)(-950 -2675);
FORCEPROP 0 LAST CDS_PHYS_NET_NAME GPU_FPGA_RST_R_N
J 0
(-210 -2633);
PAINT MONO (-210 -2633);
DISPLAY INVISIBLE (-210 -2633);
FORCEPROP 2 LAST SIG_NAME FM_PCH_SPKR_R
J 0
(-535 -2665);
DISPLAY 0.553191 (-535 -2665);
PAINT WHITE (-535 -2665);
WIRE 16 2175 (-2800 -1325)(625 -1325);
WIRE 16 2175 (625 -1325)(625 -2725);
WIRE 16 2175 (-2800 -1325)(-2800 -2725);
WIRE 16 2175 (-2800 -2725)(625 -2725);
WIRE 16 -1 (-850 -3025)(575 -3025);
FORCEPROP 0 LAST CDS_PHYS_NET_NAME CLK_25M_OSC_MAIN_FPGA
J 0
(-825 -2983);
PAINT MONO (-825 -2983);
DISPLAY INVISIBLE (-825 -2983);
FORCEPROP 0 LAST SIG_NAME CLK_25M_OSC_MAIN_FPGA
J 0
(-300 -3015);
DISPLAY 0.680851 (-300 -3015);
PAINT WHITE (-300 -3015);
WIRE 16 -1 (-2200 -2125)(-1150 -2125);
FORCEPROP 0 LAST CDS_PHYS_NET_NAME GPU_FPGA_RST_N
J 0
(-1535 -2091);
PAINT MONO (-1535 -2091);
DISPLAY INVISIBLE (-1535 -2091);
FORCEPROP 2 LAST SIG_NAME FM_JTAG_TCK_MUX_SEL_R
J 0
(-2085 -2115);
DISPLAY 0.638298 (-2085 -2115);
PAINT WHITE (-2085 -2115);
WIRE 16 -1 (-2875 -3025)(-2775 -3025);
WIRE 16 -1 (-2875 -3025)(-2875 -2575);
WIRE 16 -1 (-3000 -2575)(-3000 -2675);
WIRE 16 -1 (-3000 -2575)(-2875 -2575);
WIRE 16 -1 (-2200 -1200)(-1125 -1200);
FORCEPROP 0 LAST CDS_PHYS_NET_NAME FM_SMB_2_ALERT_GPU_ISO_N
J 0
(-2175 -1158);
PAINT MONO (-2175 -1158);
DISPLAY INVISIBLE (-2175 -1158);
FORCEPROP 0 LAST SIG_NAME FM_SMB_2_ALERT_GPU_ISO_N
J 0
(-2100 -1190);
DISPLAY 0.680851 (-2100 -1190);
PAINT WHITE (-2100 -1190);
WIRE 16 -1 (-925 -1625)(200 -1625);
FORCEPROP 0 LAST CDS_PHYS_NET_NAME FM_SMB_1_ALERT_GPU_ISO_R_N
J 0
(-610 -1585);
PAINT MONO (-610 -1585);
DISPLAY INVISIBLE (-610 -1585);
FORCEPROP 2 LAST SIG_NAME LED_HDD_ACTIVITY_B_PLD_N
J 0
(-585 -1615);
DISPLAY 0.638298 (-585 -1615);
PAINT WHITE (-585 -1615);
WIRE 16 -1 (200 -1900)(-950 -1900);
FORCEPROP 0 LAST CDS_PHYS_NET_NAME GPU_FPGA_RST_R_N
J 0
(-210 -1858);
PAINT MONO (-210 -1858);
DISPLAY INVISIBLE (-210 -1858);
FORCEPROP 2 LAST SIG_NAME GPU_FPGA_RST_R_N
J 0
(-535 -1890);
DISPLAY 0.553191 (-535 -1890);
PAINT WHITE (-535 -1890);
WIRE 16 -1 (-925 -1425)(200 -1425);
FORCEPROP 0 LAST CDS_PHYS_NET_NAME FM_SMB_2_ALERT_GPU_ISO_R_N
J 0
(-610 -1385);
PAINT MONO (-610 -1385);
DISPLAY INVISIBLE (-610 -1385);
FORCEPROP 2 LAST SIG_NAME E1S_0_LED_ACT_N
J 0
(-585 -1415);
DISPLAY 0.638298 (-585 -1415);
PAINT WHITE (-585 -1415);
WIRE 16 -1 (-2200 -1425)(-1125 -1425);
FORCEPROP 0 LAST CDS_PHYS_NET_NAME FM_SMB_2_ALERT_GPU_ISO_N
J 0
(-2175 -1383);
PAINT MONO (-2175 -1383);
DISPLAY INVISIBLE (-2175 -1383);
FORCEPROP 0 LAST SIG_NAME E1S_0_LED_ACT_R_N
J 0
(-2100 -1415);
DISPLAY 0.680851 (-2100 -1415);
PAINT WHITE (-2100 -1415);
WIRE 16 -1 (200 -2125)(-950 -2125);
FORCEPROP 0 LAST CDS_PHYS_NET_NAME GPU_FPGA_RST_R_N
J 0
(-210 -2083);
PAINT MONO (-210 -2083);
DISPLAY INVISIBLE (-210 -2083);
FORCEPROP 2 LAST SIG_NAME FM_JTAG_TCK_MUX_SEL
J 0
(-535 -2115);
DISPLAY 0.553191 (-535 -2115);
PAINT WHITE (-535 -2115);
WIRE 16 -1 (200 -2350)(-950 -2350);
FORCEPROP 0 LAST CDS_PHYS_NET_NAME GPU_FPGA_RST_R_N
J 0
(-210 -2308);
PAINT MONO (-210 -2308);
DISPLAY INVISIBLE (-210 -2308);
FORCEPROP 2 LAST SIG_NAME CLK_GEN2_GPU_FPGA_OE_N
J 0
(-535 -2340);
DISPLAY 0.553191 (-535 -2340);
PAINT WHITE (-535 -2340);
WIRE 16 -1 (200 -2525)(-950 -2525);
FORCEPROP 0 LAST CDS_PHYS_NET_NAME GPU_FPGA_RST_R_N
J 0
(-210 -2483);
PAINT MONO (-210 -2483);
DISPLAY INVISIBLE (-210 -2483);
FORCEPROP 2 LAST SIG_NAME FM_BMC_CPU_FBRK_OUT_N
J 0
(-535 -2515);
DISPLAY 0.553191 (-535 -2515);
PAINT WHITE (-535 -2515);
WIRE 16 -1 (-1200 1425)(-50 1425);
FORCEPROP 0 LAST CDS_PHYS_NET_NAME FM_PVCCFA_EHV_FIVRA_CPU1_R_EN
J 0
(-1175 1467);
PAINT MONO (-1175 1467);
DISPLAY INVISIBLE (-1175 1467);
FORCEPROP 0 LAST SIG_NAME FM_PVCCFA_EHV_FIVRA_CPU1_R_EN
J 0
(-1110 1435);
DISPLAY 0.680851 (-1110 1435);
PAINT WHITE (-1110 1435);
WIRE 16 -1 (-925 -1200)(200 -1200);
FORCEPROP 0 LAST CDS_PHYS_NET_NAME FM_SMB_2_ALERT_GPU_ISO_R_N
J 0
(-610 -1160);
PAINT MONO (-610 -1160);
DISPLAY INVISIBLE (-610 -1160);
FORCEPROP 2 LAST SIG_NAME FM_SMB_2_ALERT_GPU_ISO_R_N
J 0
(-585 -1190);
DISPLAY 0.638298 (-585 -1190);
PAINT WHITE (-585 -1190);
WIRE 16 -1 (-925 -1000)(200 -1000);
FORCEPROP 0 LAST CDS_PHYS_NET_NAME FM_SMB_1_ALERT_GPU_ISO_R_N
J 0
(-610 -960);
PAINT MONO (-610 -960);
DISPLAY INVISIBLE (-610 -960);
FORCEPROP 2 LAST SIG_NAME FM_SMB_1_ALERT_GPU_ISO_R_N
J 0
(-585 -990);
DISPLAY 0.638298 (-585 -990);
PAINT WHITE (-585 -990);
WIRE 16 -1 (-2200 -2525)(-1150 -2525);
FORCEPROP 0 LAST CDS_PHYS_NET_NAME GPU_FPGA_RST_N
J 0
(-1535 -2491);
PAINT MONO (-1535 -2491);
DISPLAY INVISIBLE (-1535 -2491);
FORCEPROP 2 LAST SIG_NAME FM_BMC_CPU_FBRK_OUT_R_N
J 0
(-2085 -2515);
DISPLAY 0.638298 (-2085 -2515);
PAINT WHITE (-2085 -2515);
WIRE 16 -1 (-2200 -2350)(-1150 -2350);
FORCEPROP 0 LAST CDS_PHYS_NET_NAME GPU_FPGA_RST_N
J 0
(-1535 -2316);
PAINT MONO (-1535 -2316);
DISPLAY INVISIBLE (-1535 -2316);
FORCEPROP 2 LAST SIG_NAME CLK_GEN2_GPU_FPGA_OE_R_N
J 0
(-2085 -2340);
DISPLAY 0.638298 (-2085 -2340);
PAINT WHITE (-2085 -2340);
WIRE 16 -1 (-2200 -2675)(-1150 -2675);
FORCEPROP 0 LAST CDS_PHYS_NET_NAME GPU_FPGA_RST_N
J 0
(-1535 -2641);
PAINT MONO (-1535 -2641);
DISPLAY INVISIBLE (-1535 -2641);
FORCEPROP 2 LAST SIG_NAME FM_PCH_SPKR
J 0
(-2085 -2665);
DISPLAY 0.638298 (-2085 -2665);
PAINT WHITE (-2085 -2665);
WIRE 16 -1 (-2200 -1900)(-1150 -1900);
FORCEPROP 0 LAST CDS_PHYS_NET_NAME GPU_FPGA_RST_N
J 0
(-1535 -1866);
PAINT MONO (-1535 -1866);
DISPLAY INVISIBLE (-1535 -1866);
FORCEPROP 2 LAST SIG_NAME GPU_FPGA_RST_N
J 0
(-2085 -1890);
DISPLAY 0.638298 (-2085 -1890);
PAINT WHITE (-2085 -1890);
WIRE 16 -1 (-3725 -3175)(-2775 -3175);
FORCEPROP 0 LAST CDS_PHYS_NET_NAME PU_CLK25M_OSC_FPGA_EN
J 0
(-3700 -3133);
PAINT MONO (-3700 -3133);
DISPLAY INVISIBLE (-3700 -3133);
FORCEPROP 0 LAST SIG_NAME PU_CLK25M_OSC_FPGA_EN
J 0
(-3660 -3165);
DISPLAY 0.680851 (-3660 -3165);
PAINT WHITE (-3660 -3165);
WIRE 16 -1 (-3725 -3050)(-3725 -3175);
WIRE 16 -1 (-2125 -3025)(-1050 -3025);
FORCEPROP 0 LAST CDS_PHYS_NET_NAME CLK_25M_OSC_FPGA_R
J 0
(-2100 -2983);
PAINT MONO (-2100 -2983);
DISPLAY INVISIBLE (-2100 -2983);
FORCEPROP 0 LAST SIG_NAME CLK_25M_OSC_FPGA_R
J 0
(-1975 -3015);
DISPLAY 0.680851 (-1975 -3015);
PAINT WHITE (-1975 -3015);
WIRE 16 -1 (1450 -1600)(2575 -1600);
FORCEPROP 0 LAST CDS_PHYS_NET_NAME VOL_SEN_ALERT
J 0
(1475 -1558);
PAINT MONO (1475 -1558);
DISPLAY INVISIBLE (1475 -1558);
FORCEPROP 0 LAST SIG_NAME FM_ESPI_PLD_R_EN
J 0
(1550 -1590);
DISPLAY 0.680851 (1550 -1590);
PAINT WHITE (1550 -1590);
WIRE 16 -1 (2575 -2850)(1450 -2850);
FORCEPROP 2 LAST SIG_NAME FM_JTAG_BMC_MUX_SEL_R
J 0
(1565 -2840);
DISPLAY 0.638298 (1565 -2840);
PAINT WHITE (1565 -2840);
WIRE 16 -1 (2775 -2650)(4175 -2650);
FORCEPROP 2 LAST SIG_NAME FM_THERMAL_ALERT_R_N
J 0
(3190 -2640);
DISPLAY 0.638298 (3190 -2640);
PAINT WHITE (3190 -2640);
WIRE 16 -1 (2575 -2950)(1450 -2950);
FORCEPROP 2 LAST SIG_NAME FM_JTAG_BMC_MUX_SEL_FROM_BMC_R
J 0
(1465 -2940);
DISPLAY 0.638298 (1465 -2940);
PAINT WHITE (1465 -2940);
WIRE 16 -1 (2775 -2950)(3100 -2950);
WIRE 16 -1 (3100 -2950)(3100 -2850);
WIRE 16 -1 (3100 -2850)(4175 -2850);
FORCEPROP 0 LAST CDS_PHYS_NET_NAME FM_JTAG_BMC_MUX_SEL
J 0
(3115 -2810);
PAINT MONO (3115 -2810);
DISPLAY INVISIBLE (3115 -2810);
FORCEPROP 2 LAST SIG_NAME FM_JTAG_BMC_MUX_SEL
J 0
(3190 -2840);
DISPLAY 0.638298 (3190 -2840);
PAINT WHITE (3190 -2840);
WIRE 16 -1 (2775 -2850)(3100 -2850);
WIRE 16 -1 (-2200 -1625)(-1125 -1625);
FORCEPROP 0 LAST CDS_PHYS_NET_NAME FM_SMB_1_ALERT_GPU_ISO_N
J 0
(-2175 -1583);
PAINT MONO (-2175 -1583);
DISPLAY INVISIBLE (-2175 -1583);
FORCEPROP 0 LAST SIG_NAME LED_HDD_ACTIVITY_B_N
J 0
(-2100 -1615);
DISPLAY 0.680851 (-2100 -1615);
PAINT WHITE (-2100 -1615);
WIRE 16 -1 (-2200 -1000)(-1125 -1000);
FORCEPROP 0 LAST CDS_PHYS_NET_NAME FM_SMB_1_ALERT_GPU_ISO_N
J 0
(-2175 -958);
PAINT MONO (-2175 -958);
DISPLAY INVISIBLE (-2175 -958);
FORCEPROP 0 LAST SIG_NAME FM_SMB_1_ALERT_GPU_ISO_N
J 0
(-2100 -990);
DISPLAY 0.680851 (-2100 -990);
PAINT WHITE (-2100 -990);
WIRE 16 -1 (2800 -1175)(4150 -1175);
FORCEPROP 0 LAST CDS_PHYS_NET_NAME IRQ_PCH_SCI_WHEA_N
J 0
(2825 -1133);
PAINT MONO (2825 -1133);
DISPLAY INVISIBLE (2825 -1133);
FORCEPROP 0 LAST SIG_NAME HP_LVC3_OCP_V3_1_HSC_PWRGD_PLD_R
J 0
(3090 -1165);
DISPLAY 0.680851 (3090 -1165);
PAINT WHITE (3090 -1165);
WIRE 16 -1 (-1200 1025)(-50 1025);
FORCEPROP 0 LAST CDS_PHYS_NET_NAME FM_PVPP_HBM_CPU0_EN
J 0
(-1175 1067);
PAINT MONO (-1175 1067);
DISPLAY INVISIBLE (-1175 1067);
FORCEPROP 0 LAST SIG_NAME FM_PVPP_HBM_CPU0_EN
J 0
(-1110 1035);
DISPLAY 0.680851 (-1110 1035);
PAINT WHITE (-1110 1035);
WIRE 16 -1 (-1200 825)(-50 825);
FORCEPROP 0 LAST CDS_PHYS_NET_NAME FM_P1V05_PCH_AUX_EN
J 0
(-1175 867);
PAINT MONO (-1175 867);
DISPLAY INVISIBLE (-1175 867);
FORCEPROP 0 LAST SIG_NAME FM_P1V05_PCH_AUX_EN
J 0
(-1110 835);
DISPLAY 0.680851 (-1110 835);
PAINT WHITE (-1110 835);
WIRE 16 -1 (1450 -2650)(2575 -2650);
FORCEPROP 2 LAST SIG_NAME FM_THERMAL_ALERT_N
J 0
(1540 -2640);
DISPLAY 0.638298 (1540 -2640);
PAINT WHITE (1540 -2640);
WIRE 16 -1 (-1200 775)(-50 775);
FORCEPROP 0 LAST CDS_PHYS_NET_NAME FM_ESPI_PLD_R_EN
J 0
(-1175 817);
PAINT MONO (-1175 817);
DISPLAY INVISIBLE (-1175 817);
FORCEPROP 0 LAST SIG_NAME FM_ESPI_PLD_R_EN
J 0
(-1110 785);
DISPLAY 0.680851 (-1110 785);
PAINT WHITE (-1110 785);
WIRE 16 -1 (-1200 875)(-50 875);
FORCEPROP 0 LAST CDS_PHYS_NET_NAME FM_P5V_EN
J 0
(-1175 917);
PAINT MONO (-1175 917);
DISPLAY INVISIBLE (-1175 917);
FORCEPROP 0 LAST SIG_NAME FM_P5V_EN
J 0
(-1110 885);
DISPLAY 0.680851 (-1110 885);
PAINT WHITE (-1110 885);
WIRE 16 -1 (-1200 925)(-50 925);
FORCEPROP 0 LAST CDS_PHYS_NET_NAME FM_PCH_P1V8_AUX_EN
J 0
(-1175 967);
PAINT MONO (-1175 967);
DISPLAY INVISIBLE (-1175 967);
FORCEPROP 0 LAST SIG_NAME FM_PCH_P1V8_AUX_EN
J 0
(-1110 935);
DISPLAY 0.680851 (-1110 935);
PAINT WHITE (-1110 935);
WIRE 16 -1 (-1200 975)(-50 975);
FORCEPROP 0 LAST CDS_PHYS_NET_NAME FM_AUX_SW_EN
J 0
(-1175 1017);
PAINT MONO (-1175 1017);
DISPLAY INVISIBLE (-1175 1017);
FORCEPROP 0 LAST SIG_NAME FM_AUX_SW_EN
J 0
(-1110 985);
DISPLAY 0.680851 (-1110 985);
PAINT WHITE (-1110 985);
WIRE 16 -1 (-1200 1125)(-50 1125);
FORCEPROP 0 LAST CDS_PHYS_NET_NAME FM_PVCCIN_CPU1_R_EN
J 0
(-1175 1167);
PAINT MONO (-1175 1167);
DISPLAY INVISIBLE (-1175 1167);
FORCEPROP 0 LAST SIG_NAME FM_PVCCIN_CPU1_R_EN
J 0
(-1110 1135);
DISPLAY 0.680851 (-1110 1135);
PAINT WHITE (-1110 1135);
WIRE 16 -1 (-1200 1175)(-50 1175);
FORCEPROP 0 LAST CDS_PHYS_NET_NAME FM_PVCCIN_CPU0_R_EN
J 0
(-1175 1217);
PAINT MONO (-1175 1217);
DISPLAY INVISIBLE (-1175 1217);
FORCEPROP 0 LAST SIG_NAME FM_PVCCIN_CPU0_R_EN
J 0
(-1110 1185);
DISPLAY 0.680851 (-1110 1185);
PAINT WHITE (-1110 1185);
WIRE 16 -1 (-1200 1225)(-50 1225);
FORCEPROP 0 LAST CDS_PHYS_NET_NAME FM_PVNN_MAIN_CPU1_EN
J 0
(-1175 1267);
PAINT MONO (-1175 1267);
DISPLAY INVISIBLE (-1175 1267);
FORCEPROP 0 LAST SIG_NAME FM_PVNN_MAIN_CPU1_EN
J 0
(-1110 1235);
DISPLAY 0.680851 (-1110 1235);
PAINT WHITE (-1110 1235);
WIRE 16 -1 (-1200 1075)(-50 1075);
FORCEPROP 0 LAST CDS_PHYS_NET_NAME FM_PVPP_HBM_CPU1_EN
J 0
(-1175 1117);
PAINT MONO (-1175 1117);
DISPLAY INVISIBLE (-1175 1117);
FORCEPROP 0 LAST SIG_NAME FM_PVPP_HBM_CPU1_EN
J 0
(-1110 1085);
DISPLAY 0.680851 (-1110 1085);
PAINT WHITE (-1110 1085);
WIRE 16 -1 (1200 1675)(2350 1675);
FORCEPROP 0 LAST CDS_PHYS_NET_NAME SMB_2_PLD_3V3AUX_SCL
J 0
(1225 1717);
PAINT MONO (1225 1717);
DISPLAY INVISIBLE (1225 1717);
FORCEPROP 0 LAST SIG_NAME SMB_2_PLD_3V3AUX_SCL_R1
J 0
(1340 1685);
DISPLAY 0.680851 (1340 1685);
PAINT WHITE (1340 1685);
WIRE 16 -1 (1200 1625)(2350 1625);
FORCEPROP 0 LAST CDS_PHYS_NET_NAME SMB_2_PLD_3V3AUX_SDA
J 0
(1225 1667);
PAINT MONO (1225 1667);
DISPLAY INVISIBLE (1225 1667);
FORCEPROP 0 LAST SIG_NAME SMB_2_PLD_3V3AUX_SDA_R1
J 0
(1340 1635);
DISPLAY 0.680851 (1340 1635);
PAINT WHITE (1340 1635);
WIRE 16 -1 (1200 1575)(2350 1575);
FORCEPROP 0 LAST CDS_PHYS_NET_NAME RST_PCIE_CPU0_DEV_PERST_N
J 0
(1225 1617);
PAINT MONO (1225 1617);
DISPLAY INVISIBLE (1225 1617);
FORCEPROP 0 LAST SIG_NAME RST_PCIE_CPU0_DEV_PERST_N
J 0
(1340 1585);
DISPLAY 0.680851 (1340 1585);
PAINT WHITE (1340 1585);
WIRE 16 -1 (-1200 1475)(-50 1475);
FORCEPROP 0 LAST CDS_PHYS_NET_NAME FM_PVCCFA_EHV_FIVRA_CPU0_R_EN
J 0
(-1175 1517);
PAINT MONO (-1175 1517);
DISPLAY INVISIBLE (-1175 1517);
FORCEPROP 0 LAST SIG_NAME FM_PVCCFA_EHV_FIVRA_CPU0_R_EN
J 0
(-1110 1485);
DISPLAY 0.680851 (-1110 1485);
PAINT WHITE (-1110 1485);
WIRE 16 -1 (-1200 1525)(-50 1525);
FORCEPROP 0 LAST CDS_PHYS_NET_NAME FM_PVCCFA_EHV_CPU1_R_EN
J 0
(-1175 1567);
PAINT MONO (-1175 1567);
DISPLAY INVISIBLE (-1175 1567);
FORCEPROP 0 LAST SIG_NAME FM_PVCCFA_EHV_CPU1_R_EN
J 0
(-1110 1535);
DISPLAY 0.680851 (-1110 1535);
PAINT WHITE (-1110 1535);
WIRE 16 -1 (-1200 1575)(-50 1575);
FORCEPROP 0 LAST CDS_PHYS_NET_NAME FM_PVCCFA_EHV_CPU0_R_EN
J 0
(-1175 1617);
PAINT MONO (-1175 1617);
DISPLAY INVISIBLE (-1175 1617);
FORCEPROP 0 LAST SIG_NAME FM_PVCCFA_EHV_CPU0_R_EN
J 0
(-1110 1585);
DISPLAY 0.680851 (-1110 1585);
PAINT WHITE (-1110 1585);
WIRE 16 -1 (-1200 1675)(-50 1675);
FORCEPROP 0 LAST CDS_PHYS_NET_NAME FM_PVCCD_HV_CPU0_EN
J 0
(-1175 1717);
PAINT MONO (-1175 1717);
DISPLAY INVISIBLE (-1175 1717);
FORCEPROP 0 LAST SIG_NAME FM_PVCCD_HV_CPU0_EN
J 0
(-1110 1685);
DISPLAY 0.680851 (-1110 1685);
PAINT WHITE (-1110 1685);
WIRE 16 -1 (-1200 1325)(-50 1325);
FORCEPROP 0 LAST CDS_PHYS_NET_NAME FM_PVCCINFAON_CPU1_R_EN
J 0
(-1175 1367);
PAINT MONO (-1175 1367);
DISPLAY INVISIBLE (-1175 1367);
FORCEPROP 0 LAST SIG_NAME FM_PVCCINFAON_CPU1_R_EN
J 0
(-1110 1335);
DISPLAY 0.680851 (-1110 1335);
PAINT WHITE (-1110 1335);
WIRE 16 -1 (-1200 1275)(-50 1275);
FORCEPROP 0 LAST CDS_PHYS_NET_NAME FM_PVNN_MAIN_CPU0_EN
J 0
(-1175 1317);
PAINT MONO (-1175 1317);
DISPLAY INVISIBLE (-1175 1317);
FORCEPROP 0 LAST SIG_NAME FM_PVNN_MAIN_CPU0_EN
J 0
(-1110 1285);
DISPLAY 0.680851 (-1110 1285);
PAINT WHITE (-1110 1285);
DOT 1 (-3000 -2575);
DOT 1 (2300 -1800);
DOT 1 (3100 -2850);
FORCENOTE
20220113 ADD R4599,R4600
(3275 -800) 0;
DISPLAY LEFT (3275 -800);
DISPLAY 1.063830 (3275 -800);
PAINT WHITE (3275 -800);
FORCENOTE
20210902 MODIFY FOR GT
(-4250 2275) 0;
DISPLAY LEFT (-4250 2275);
DISPLAY 2.510638 (-4250 2275);
PAINT PINK (-4250 2275);
FORCENOTE
20220224 ADD R4606,R4607,R4608,R4609,R4610,R4611,R4612
(-2400 -1300) 0;
DISPLAY LEFT (-2400 -1300);
DISPLAY 1.063830 (-2400 -1300);
PAINT WHITE (-2400 -1300);
QUIT
